FILE_TYPE = MACRO_DRAWING;
SET COLOR_WIRE YELLOW;
SET COLOR_PROP ORANGE;
SET COLOR_DOT WHITE;
SET COLOR_ARC YELLOW;
SET COLOR_BODY GREEN;
SET COLOR_NOTE PURPLE;
SET PROP_DISPLAY VALUE;
SET PAGE_NUMBER P107;
FORCEADD OFFPAGE..5
(-8300 1875);
FORCEPROP 2 LAST $XR0 47 
J 0
(-8554 1875);
DISPLAY 0.638298 (-8554 1875);
PAINT MONO (-8554 1875);
FORCEPROP 2 LAST CDS_LIB mstr_standard
J 0
(-8300 1875);
DISPLAY 0.808511 (-8300 1875);
DISPLAY INVISIBLE (-8300 1875);
FORCEPROP 1 LAST OFFPAGE TRUE
J 0
(-7975 1750);
DISPLAY 0.872340 (-7975 1750);
PAINT GREEN (-7975 1750);
DISPLAY INVISIBLE (-7975 1750);
FORCEPROP 1 LAST COMMENT_BODY TRUE
J 0
(-8200 1800);
DISPLAY 0.872340 (-8200 1800);
PAINT GREEN (-8200 1800);
DISPLAY INVISIBLE (-8200 1800);
FORCEPROP 2 LAST PATH I1
J 0
(-8550 1925);
DISPLAY 1.021277 (-8550 1925);
DISPLAY INVISIBLE (-8550 1925);
FORCEADD OFFPAGE..6
(-8300 3525);
FORCEPROP 2 LAST $XR0 47 
J 0
(-8549 3525);
DISPLAY 0.638298 (-8549 3525);
PAINT MONO (-8549 3525);
FORCEPROP 2 LAST CDS_LIB mstr_standard
J 0
(-8300 3525);
DISPLAY 0.723404 (-8300 3525);
PAINT MONO (-8300 3525);
DISPLAY INVISIBLE (-8300 3525);
FORCEPROP 1 LAST OFFPAGE TRUE
J 0
(-7975 3400);
DISPLAY 0.872340 (-7975 3400);
PAINT GREEN (-7975 3400);
DISPLAY INVISIBLE (-7975 3400);
FORCEPROP 1 LAST COMMENT_BODY TRUE
J 0
(-8200 3450);
DISPLAY 0.872340 (-8200 3450);
PAINT GREEN (-8200 3450);
DISPLAY INVISIBLE (-8200 3450);
FORCEPROP 2 LAST PATH I10
J 0
(-8575 3575);
DISPLAY 1.021277 (-8575 3575);
DISPLAY INVISIBLE (-8575 3575);
FORCEADD TAP..1
(-6000 4175);
FORCEPROP 3 LASTPIN (-6050 4175) SIG_NAME M_K_CPU1_SA_DQ<8>
J 0
(-6040 4185);
DISPLAY 0.659574 (-6040 4185);
PAINT MONO (-6040 4185);
DISPLAY INVISIBLE (-6040 4185);
FORCEPROP 1 LASTPIN (-6050 4175) BN 8
J 0
(-6062 4183);
DISPLAY 0.489362 (-6062 4183);
PAINT GREEN (-6062 4183);
FORCEPROP 2 LAST CDS_LIB mstr_standard
J 0
(-6000 4175);
DISPLAY 0.723404 (-6000 4175);
PAINT MONO (-6000 4175);
DISPLAY INVISIBLE (-6000 4175);
FORCEPROP 1 LAST BODY_TYPE PLUMBING
J 0
(-6000 4225);
DISPLAY 0.872340 (-6000 4225);
PAINT GREEN (-6000 4225);
DISPLAY INVISIBLE (-6000 4225);
FORCEPROP 1 LAST HDL_TAP TRUE
J 0
(-5675 4050);
DISPLAY 0.872340 (-5675 4050);
DISPLAY INVISIBLE (-5675 4050);
FORCEPROP 1 LAST PATH I100
J 0
(-6002 4175);
DISPLAY 0.872340 (-6002 4175);
PAINT GREEN (-6002 4175);
DISPLAY INVISIBLE (-6002 4175);
FORCEADD TAP..1
(-6000 4225);
FORCEPROP 3 LASTPIN (-6050 4225) SIG_NAME M_K_CPU1_SA_DQ<9>
J 0
(-6040 4235);
DISPLAY 0.659574 (-6040 4235);
PAINT MONO (-6040 4235);
DISPLAY INVISIBLE (-6040 4235);
FORCEPROP 1 LASTPIN (-6050 4225) BN 9
J 0
(-6062 4233);
DISPLAY 0.489362 (-6062 4233);
PAINT GREEN (-6062 4233);
FORCEPROP 2 LAST CDS_LIB mstr_standard
J 0
(-6000 4225);
DISPLAY 0.723404 (-6000 4225);
PAINT MONO (-6000 4225);
DISPLAY INVISIBLE (-6000 4225);
FORCEPROP 1 LAST BODY_TYPE PLUMBING
J 0
(-6000 4275);
DISPLAY 0.872340 (-6000 4275);
PAINT GREEN (-6000 4275);
DISPLAY INVISIBLE (-6000 4275);
FORCEPROP 1 LAST HDL_TAP TRUE
J 0
(-5675 4100);
DISPLAY 0.872340 (-5675 4100);
DISPLAY INVISIBLE (-5675 4100);
FORCEPROP 1 LAST PATH I101
J 0
(-6002 4225);
DISPLAY 0.872340 (-6002 4225);
PAINT GREEN (-6002 4225);
DISPLAY INVISIBLE (-6002 4225);
FORCEADD TAP..1
(-6000 4275);
FORCEPROP 3 LASTPIN (-6050 4275) SIG_NAME M_K_CPU1_SA_DQ<10>
J 0
(-6040 4285);
DISPLAY 0.659574 (-6040 4285);
PAINT MONO (-6040 4285);
DISPLAY INVISIBLE (-6040 4285);
FORCEPROP 1 LASTPIN (-6050 4275) BN 10
J 0
(-6062 4283);
DISPLAY 0.489362 (-6062 4283);
PAINT GREEN (-6062 4283);
FORCEPROP 2 LAST CDS_LIB mstr_standard
J 0
(-6000 4275);
DISPLAY 0.723404 (-6000 4275);
PAINT MONO (-6000 4275);
DISPLAY INVISIBLE (-6000 4275);
FORCEPROP 1 LAST BODY_TYPE PLUMBING
J 0
(-6000 4325);
DISPLAY 0.872340 (-6000 4325);
PAINT GREEN (-6000 4325);
DISPLAY INVISIBLE (-6000 4325);
FORCEPROP 1 LAST HDL_TAP TRUE
J 0
(-5675 4150);
DISPLAY 0.872340 (-5675 4150);
DISPLAY INVISIBLE (-5675 4150);
FORCEPROP 1 LAST PATH I102
J 0
(-6002 4275);
DISPLAY 0.872340 (-6002 4275);
PAINT GREEN (-6002 4275);
DISPLAY INVISIBLE (-6002 4275);
FORCEADD TAP..1
(-6000 4375);
FORCEPROP 3 LASTPIN (-6050 4375) SIG_NAME M_K_CPU1_SA_DQ<12>
J 0
(-6040 4385);
DISPLAY 0.659574 (-6040 4385);
PAINT MONO (-6040 4385);
DISPLAY INVISIBLE (-6040 4385);
FORCEPROP 1 LASTPIN (-6050 4375) BN 12
J 0
(-6062 4383);
DISPLAY 0.489362 (-6062 4383);
PAINT GREEN (-6062 4383);
FORCEPROP 2 LAST CDS_LIB mstr_standard
J 0
(-6000 4375);
DISPLAY 0.723404 (-6000 4375);
PAINT MONO (-6000 4375);
DISPLAY INVISIBLE (-6000 4375);
FORCEPROP 1 LAST BODY_TYPE PLUMBING
J 0
(-6000 4425);
DISPLAY 0.872340 (-6000 4425);
PAINT GREEN (-6000 4425);
DISPLAY INVISIBLE (-6000 4425);
FORCEPROP 1 LAST HDL_TAP TRUE
J 0
(-5675 4250);
DISPLAY 0.872340 (-5675 4250);
DISPLAY INVISIBLE (-5675 4250);
FORCEPROP 1 LAST PATH I103
J 0
(-6002 4375);
DISPLAY 0.872340 (-6002 4375);
PAINT GREEN (-6002 4375);
DISPLAY INVISIBLE (-6002 4375);
FORCEADD TAP..1
(-6000 4325);
FORCEPROP 3 LASTPIN (-6050 4325) SIG_NAME M_K_CPU1_SA_DQ<11>
J 0
(-6040 4335);
DISPLAY 0.659574 (-6040 4335);
PAINT MONO (-6040 4335);
DISPLAY INVISIBLE (-6040 4335);
FORCEPROP 1 LASTPIN (-6050 4325) BN 11
J 0
(-6062 4333);
DISPLAY 0.489362 (-6062 4333);
PAINT GREEN (-6062 4333);
FORCEPROP 2 LAST CDS_LIB mstr_standard
J 0
(-6000 4325);
DISPLAY 0.723404 (-6000 4325);
PAINT MONO (-6000 4325);
DISPLAY INVISIBLE (-6000 4325);
FORCEPROP 1 LAST BODY_TYPE PLUMBING
J 0
(-6000 4375);
DISPLAY 0.872340 (-6000 4375);
PAINT GREEN (-6000 4375);
DISPLAY INVISIBLE (-6000 4375);
FORCEPROP 1 LAST HDL_TAP TRUE
J 0
(-5675 4200);
DISPLAY 0.872340 (-5675 4200);
DISPLAY INVISIBLE (-5675 4200);
FORCEPROP 1 LAST PATH I104
J 0
(-6002 4325);
DISPLAY 0.872340 (-6002 4325);
PAINT GREEN (-6002 4325);
DISPLAY INVISIBLE (-6002 4325);
FORCEADD TAP..1
(-6000 4425);
FORCEPROP 3 LASTPIN (-6050 4425) SIG_NAME M_K_CPU1_SA_DQ<13>
J 0
(-6040 4435);
DISPLAY 0.659574 (-6040 4435);
PAINT MONO (-6040 4435);
DISPLAY INVISIBLE (-6040 4435);
FORCEPROP 1 LASTPIN (-6050 4425) BN 13
J 0
(-6062 4433);
DISPLAY 0.489362 (-6062 4433);
PAINT GREEN (-6062 4433);
FORCEPROP 2 LAST CDS_LIB mstr_standard
J 0
(-6000 4425);
DISPLAY 0.723404 (-6000 4425);
PAINT MONO (-6000 4425);
DISPLAY INVISIBLE (-6000 4425);
FORCEPROP 1 LAST BODY_TYPE PLUMBING
J 0
(-6000 4475);
DISPLAY 0.872340 (-6000 4475);
PAINT GREEN (-6000 4475);
DISPLAY INVISIBLE (-6000 4475);
FORCEPROP 1 LAST HDL_TAP TRUE
J 0
(-5675 4300);
DISPLAY 0.872340 (-5675 4300);
DISPLAY INVISIBLE (-5675 4300);
FORCEPROP 1 LAST PATH I105
J 0
(-6002 4425);
DISPLAY 0.872340 (-6002 4425);
PAINT GREEN (-6002 4425);
DISPLAY INVISIBLE (-6002 4425);
FORCEADD TAP..1
(-6000 4475);
FORCEPROP 3 LASTPIN (-6050 4475) SIG_NAME M_K_CPU1_SA_DQ<14>
J 0
(-6040 4485);
DISPLAY 0.659574 (-6040 4485);
PAINT MONO (-6040 4485);
DISPLAY INVISIBLE (-6040 4485);
FORCEPROP 1 LASTPIN (-6050 4475) BN 14
J 0
(-6062 4483);
DISPLAY 0.489362 (-6062 4483);
PAINT GREEN (-6062 4483);
FORCEPROP 2 LAST CDS_LIB mstr_standard
J 0
(-6000 4475);
DISPLAY 0.723404 (-6000 4475);
PAINT MONO (-6000 4475);
DISPLAY INVISIBLE (-6000 4475);
FORCEPROP 1 LAST BODY_TYPE PLUMBING
J 0
(-6000 4525);
DISPLAY 0.872340 (-6000 4525);
PAINT GREEN (-6000 4525);
DISPLAY INVISIBLE (-6000 4525);
FORCEPROP 1 LAST HDL_TAP TRUE
J 0
(-5675 4350);
DISPLAY 0.872340 (-5675 4350);
DISPLAY INVISIBLE (-5675 4350);
FORCEPROP 1 LAST PATH I106
J 0
(-6002 4475);
DISPLAY 0.872340 (-6002 4475);
PAINT GREEN (-6002 4475);
DISPLAY INVISIBLE (-6002 4475);
FORCEADD TAP..1
(-6000 4525);
FORCEPROP 3 LASTPIN (-6050 4525) SIG_NAME M_K_CPU1_SA_DQ<15>
J 0
(-6040 4535);
DISPLAY 0.659574 (-6040 4535);
PAINT MONO (-6040 4535);
DISPLAY INVISIBLE (-6040 4535);
FORCEPROP 1 LASTPIN (-6050 4525) BN 15
J 0
(-6062 4533);
DISPLAY 0.489362 (-6062 4533);
PAINT GREEN (-6062 4533);
FORCEPROP 2 LAST CDS_LIB mstr_standard
J 0
(-6000 4525);
DISPLAY 0.723404 (-6000 4525);
PAINT MONO (-6000 4525);
DISPLAY INVISIBLE (-6000 4525);
FORCEPROP 1 LAST BODY_TYPE PLUMBING
J 0
(-6000 4575);
DISPLAY 0.872340 (-6000 4575);
PAINT GREEN (-6000 4575);
DISPLAY INVISIBLE (-6000 4575);
FORCEPROP 1 LAST HDL_TAP TRUE
J 0
(-5675 4400);
DISPLAY 0.872340 (-5675 4400);
DISPLAY INVISIBLE (-5675 4400);
FORCEPROP 1 LAST PATH I107
J 0
(-6002 4525);
DISPLAY 0.872340 (-6002 4525);
PAINT GREEN (-6002 4525);
DISPLAY INVISIBLE (-6002 4525);
FORCEADD TAP..1
(-6000 4575);
FORCEPROP 3 LASTPIN (-6050 4575) SIG_NAME M_K_CPU1_SA_DQ<16>
J 0
(-6040 4585);
DISPLAY 0.659574 (-6040 4585);
PAINT MONO (-6040 4585);
DISPLAY INVISIBLE (-6040 4585);
FORCEPROP 1 LASTPIN (-6050 4575) BN 16
J 0
(-6062 4583);
DISPLAY 0.489362 (-6062 4583);
PAINT GREEN (-6062 4583);
FORCEPROP 2 LAST CDS_LIB mstr_standard
J 0
(-6000 4575);
DISPLAY 0.723404 (-6000 4575);
PAINT MONO (-6000 4575);
DISPLAY INVISIBLE (-6000 4575);
FORCEPROP 1 LAST BODY_TYPE PLUMBING
J 0
(-6000 4625);
DISPLAY 0.872340 (-6000 4625);
PAINT GREEN (-6000 4625);
DISPLAY INVISIBLE (-6000 4625);
FORCEPROP 1 LAST HDL_TAP TRUE
J 0
(-5675 4450);
DISPLAY 0.872340 (-5675 4450);
DISPLAY INVISIBLE (-5675 4450);
FORCEPROP 1 LAST PATH I108
J 0
(-6002 4575);
DISPLAY 0.872340 (-6002 4575);
PAINT GREEN (-6002 4575);
DISPLAY INVISIBLE (-6002 4575);
FORCEADD TAP..1
(-6000 4675);
FORCEPROP 3 LASTPIN (-6050 4675) SIG_NAME M_K_CPU1_SA_DQ<18>
J 0
(-6040 4685);
DISPLAY 0.659574 (-6040 4685);
PAINT MONO (-6040 4685);
DISPLAY INVISIBLE (-6040 4685);
FORCEPROP 1 LASTPIN (-6050 4675) BN 18
J 0
(-6062 4683);
DISPLAY 0.489362 (-6062 4683);
PAINT GREEN (-6062 4683);
FORCEPROP 2 LAST CDS_LIB mstr_standard
J 0
(-6000 4675);
DISPLAY 0.723404 (-6000 4675);
PAINT MONO (-6000 4675);
DISPLAY INVISIBLE (-6000 4675);
FORCEPROP 1 LAST BODY_TYPE PLUMBING
J 0
(-6000 4725);
DISPLAY 0.872340 (-6000 4725);
PAINT GREEN (-6000 4725);
DISPLAY INVISIBLE (-6000 4725);
FORCEPROP 1 LAST HDL_TAP TRUE
J 0
(-5675 4550);
DISPLAY 0.872340 (-5675 4550);
DISPLAY INVISIBLE (-5675 4550);
FORCEPROP 1 LAST PATH I109
J 0
(-6002 4675);
DISPLAY 0.872340 (-6002 4675);
PAINT GREEN (-6002 4675);
DISPLAY INVISIBLE (-6002 4675);
FORCEADD OFFPAGE..1
(-8300 4075);
FORCEPROP 2 LAST $XR0 47 
J 0
(-8521 4075);
DISPLAY 0.638298 (-8521 4075);
PAINT MONO (-8521 4075);
FORCEPROP 2 LAST CDS_LIB mstr_standard
J 0
(-8300 4075);
DISPLAY 0.723404 (-8300 4075);
PAINT MONO (-8300 4075);
DISPLAY INVISIBLE (-8300 4075);
FORCEPROP 1 LAST OFFPAGE TRUE
J 0
(-7975 3950);
DISPLAY 0.872340 (-7975 3950);
PAINT GREEN (-7975 3950);
DISPLAY INVISIBLE (-7975 3950);
FORCEPROP 1 LAST COMMENT_BODY TRUE
J 0
(-8175 3975);
DISPLAY 0.872340 (-8175 3975);
PAINT GREEN (-8175 3975);
DISPLAY INVISIBLE (-8175 3975);
FORCEPROP 2 LAST PATH I11
J 0
(-8500 4125);
DISPLAY 1.021277 (-8500 4125);
DISPLAY INVISIBLE (-8500 4125);
FORCEADD TAP..1
(-6000 4625);
FORCEPROP 3 LASTPIN (-6050 4625) SIG_NAME M_K_CPU1_SA_DQ<17>
J 0
(-6040 4635);
DISPLAY 0.659574 (-6040 4635);
PAINT MONO (-6040 4635);
DISPLAY INVISIBLE (-6040 4635);
FORCEPROP 1 LASTPIN (-6050 4625) BN 17
J 0
(-6062 4633);
DISPLAY 0.489362 (-6062 4633);
PAINT GREEN (-6062 4633);
FORCEPROP 2 LAST CDS_LIB mstr_standard
J 0
(-6000 4625);
DISPLAY 0.723404 (-6000 4625);
PAINT MONO (-6000 4625);
DISPLAY INVISIBLE (-6000 4625);
FORCEPROP 1 LAST BODY_TYPE PLUMBING
J 0
(-6000 4675);
DISPLAY 0.872340 (-6000 4675);
PAINT GREEN (-6000 4675);
DISPLAY INVISIBLE (-6000 4675);
FORCEPROP 1 LAST HDL_TAP TRUE
J 0
(-5675 4500);
DISPLAY 0.872340 (-5675 4500);
DISPLAY INVISIBLE (-5675 4500);
FORCEPROP 1 LAST PATH I110
J 0
(-6002 4625);
DISPLAY 0.872340 (-6002 4625);
PAINT GREEN (-6002 4625);
DISPLAY INVISIBLE (-6002 4625);
FORCEADD TAP..1
(-6000 4725);
FORCEPROP 3 LASTPIN (-6050 4725) SIG_NAME M_K_CPU1_SA_DQ<19>
J 0
(-6040 4735);
DISPLAY 0.659574 (-6040 4735);
PAINT MONO (-6040 4735);
DISPLAY INVISIBLE (-6040 4735);
FORCEPROP 1 LASTPIN (-6050 4725) BN 19
J 0
(-6062 4733);
DISPLAY 0.489362 (-6062 4733);
PAINT GREEN (-6062 4733);
FORCEPROP 2 LAST CDS_LIB mstr_standard
J 0
(-6000 4725);
DISPLAY 0.723404 (-6000 4725);
PAINT MONO (-6000 4725);
DISPLAY INVISIBLE (-6000 4725);
FORCEPROP 1 LAST BODY_TYPE PLUMBING
J 0
(-6000 4775);
DISPLAY 0.872340 (-6000 4775);
PAINT GREEN (-6000 4775);
DISPLAY INVISIBLE (-6000 4775);
FORCEPROP 1 LAST HDL_TAP TRUE
J 0
(-5675 4600);
DISPLAY 0.872340 (-5675 4600);
DISPLAY INVISIBLE (-5675 4600);
FORCEPROP 1 LAST PATH I111
J 0
(-6002 4725);
DISPLAY 0.872340 (-6002 4725);
PAINT GREEN (-6002 4725);
DISPLAY INVISIBLE (-6002 4725);
FORCEADD TAP..1
(-6000 4775);
FORCEPROP 3 LASTPIN (-6050 4775) SIG_NAME M_K_CPU1_SA_DQ<20>
J 0
(-6040 4785);
DISPLAY 0.659574 (-6040 4785);
PAINT MONO (-6040 4785);
DISPLAY INVISIBLE (-6040 4785);
FORCEPROP 1 LASTPIN (-6050 4775) BN 20
J 0
(-6062 4783);
DISPLAY 0.489362 (-6062 4783);
PAINT GREEN (-6062 4783);
FORCEPROP 2 LAST CDS_LIB mstr_standard
J 0
(-6000 4775);
DISPLAY 0.723404 (-6000 4775);
PAINT MONO (-6000 4775);
DISPLAY INVISIBLE (-6000 4775);
FORCEPROP 1 LAST BODY_TYPE PLUMBING
J 0
(-6000 4825);
DISPLAY 0.872340 (-6000 4825);
PAINT GREEN (-6000 4825);
DISPLAY INVISIBLE (-6000 4825);
FORCEPROP 1 LAST HDL_TAP TRUE
J 0
(-5675 4650);
DISPLAY 0.872340 (-5675 4650);
DISPLAY INVISIBLE (-5675 4650);
FORCEPROP 1 LAST PATH I112
J 0
(-6002 4775);
DISPLAY 0.872340 (-6002 4775);
PAINT GREEN (-6002 4775);
DISPLAY INVISIBLE (-6002 4775);
FORCEADD TAP..1
(-6000 4825);
FORCEPROP 3 LASTPIN (-6050 4825) SIG_NAME M_K_CPU1_SA_DQ<21>
J 0
(-6040 4835);
DISPLAY 0.659574 (-6040 4835);
PAINT MONO (-6040 4835);
DISPLAY INVISIBLE (-6040 4835);
FORCEPROP 1 LASTPIN (-6050 4825) BN 21
J 0
(-6062 4833);
DISPLAY 0.489362 (-6062 4833);
PAINT GREEN (-6062 4833);
FORCEPROP 2 LAST CDS_LIB mstr_standard
J 0
(-6000 4825);
DISPLAY 0.723404 (-6000 4825);
PAINT MONO (-6000 4825);
DISPLAY INVISIBLE (-6000 4825);
FORCEPROP 1 LAST BODY_TYPE PLUMBING
J 0
(-6000 4875);
DISPLAY 0.872340 (-6000 4875);
PAINT GREEN (-6000 4875);
DISPLAY INVISIBLE (-6000 4875);
FORCEPROP 1 LAST HDL_TAP TRUE
J 0
(-5675 4700);
DISPLAY 0.872340 (-5675 4700);
DISPLAY INVISIBLE (-5675 4700);
FORCEPROP 1 LAST PATH I113
J 0
(-6002 4825);
DISPLAY 0.872340 (-6002 4825);
PAINT GREEN (-6002 4825);
DISPLAY INVISIBLE (-6002 4825);
FORCEADD TAP..1
(-6000 4875);
FORCEPROP 3 LASTPIN (-6050 4875) SIG_NAME M_K_CPU1_SA_DQ<22>
J 0
(-6040 4885);
DISPLAY 0.659574 (-6040 4885);
PAINT MONO (-6040 4885);
DISPLAY INVISIBLE (-6040 4885);
FORCEPROP 1 LASTPIN (-6050 4875) BN 22
J 0
(-6062 4883);
DISPLAY 0.489362 (-6062 4883);
PAINT GREEN (-6062 4883);
FORCEPROP 2 LAST CDS_LIB mstr_standard
J 0
(-6000 4875);
DISPLAY 0.723404 (-6000 4875);
PAINT MONO (-6000 4875);
DISPLAY INVISIBLE (-6000 4875);
FORCEPROP 1 LAST BODY_TYPE PLUMBING
J 0
(-6000 4925);
DISPLAY 0.872340 (-6000 4925);
PAINT GREEN (-6000 4925);
DISPLAY INVISIBLE (-6000 4925);
FORCEPROP 1 LAST HDL_TAP TRUE
J 0
(-5675 4750);
DISPLAY 0.872340 (-5675 4750);
DISPLAY INVISIBLE (-5675 4750);
FORCEPROP 1 LAST PATH I114
J 0
(-6002 4875);
DISPLAY 0.872340 (-6002 4875);
PAINT GREEN (-6002 4875);
DISPLAY INVISIBLE (-6002 4875);
FORCEADD TAP..1
(-6000 4925);
FORCEPROP 3 LASTPIN (-6050 4925) SIG_NAME M_K_CPU1_SA_DQ<23>
J 0
(-6040 4935);
DISPLAY 0.659574 (-6040 4935);
PAINT MONO (-6040 4935);
DISPLAY INVISIBLE (-6040 4935);
FORCEPROP 1 LASTPIN (-6050 4925) BN 23
J 0
(-6062 4933);
DISPLAY 0.489362 (-6062 4933);
PAINT GREEN (-6062 4933);
FORCEPROP 2 LAST CDS_LIB mstr_standard
J 0
(-6000 4925);
DISPLAY 0.723404 (-6000 4925);
PAINT MONO (-6000 4925);
DISPLAY INVISIBLE (-6000 4925);
FORCEPROP 1 LAST BODY_TYPE PLUMBING
J 0
(-6000 4975);
DISPLAY 0.872340 (-6000 4975);
PAINT GREEN (-6000 4975);
DISPLAY INVISIBLE (-6000 4975);
FORCEPROP 1 LAST HDL_TAP TRUE
J 0
(-5675 4800);
DISPLAY 0.872340 (-5675 4800);
DISPLAY INVISIBLE (-5675 4800);
FORCEPROP 1 LAST PATH I115
J 0
(-6002 4925);
DISPLAY 0.872340 (-6002 4925);
PAINT GREEN (-6002 4925);
DISPLAY INVISIBLE (-6002 4925);
FORCEADD TAP..1
(-6000 4975);
FORCEPROP 3 LASTPIN (-6050 4975) SIG_NAME M_K_CPU1_SA_DQ<24>
J 0
(-6040 4985);
DISPLAY 0.659574 (-6040 4985);
PAINT MONO (-6040 4985);
DISPLAY INVISIBLE (-6040 4985);
FORCEPROP 1 LASTPIN (-6050 4975) BN 24
J 0
(-6062 4983);
DISPLAY 0.489362 (-6062 4983);
PAINT GREEN (-6062 4983);
FORCEPROP 2 LAST CDS_LIB mstr_standard
J 0
(-6000 4975);
DISPLAY 0.723404 (-6000 4975);
PAINT MONO (-6000 4975);
DISPLAY INVISIBLE (-6000 4975);
FORCEPROP 1 LAST BODY_TYPE PLUMBING
J 0
(-6000 5025);
DISPLAY 0.872340 (-6000 5025);
PAINT GREEN (-6000 5025);
DISPLAY INVISIBLE (-6000 5025);
FORCEPROP 1 LAST HDL_TAP TRUE
J 0
(-5675 4850);
DISPLAY 0.872340 (-5675 4850);
DISPLAY INVISIBLE (-5675 4850);
FORCEPROP 1 LAST PATH I116
J 0
(-6002 4975);
DISPLAY 0.872340 (-6002 4975);
PAINT GREEN (-6002 4975);
DISPLAY INVISIBLE (-6002 4975);
FORCEADD TAP..1
(-6000 5025);
FORCEPROP 3 LASTPIN (-6050 5025) SIG_NAME M_K_CPU1_SA_DQ<25>
J 0
(-6040 5035);
DISPLAY 0.659574 (-6040 5035);
PAINT MONO (-6040 5035);
DISPLAY INVISIBLE (-6040 5035);
FORCEPROP 1 LASTPIN (-6050 5025) BN 25
J 0
(-6062 5033);
DISPLAY 0.489362 (-6062 5033);
PAINT GREEN (-6062 5033);
FORCEPROP 2 LAST CDS_LIB mstr_standard
J 0
(-6000 5025);
DISPLAY 0.723404 (-6000 5025);
PAINT MONO (-6000 5025);
DISPLAY INVISIBLE (-6000 5025);
FORCEPROP 1 LAST BODY_TYPE PLUMBING
J 0
(-6000 5075);
DISPLAY 0.872340 (-6000 5075);
PAINT GREEN (-6000 5075);
DISPLAY INVISIBLE (-6000 5075);
FORCEPROP 1 LAST HDL_TAP TRUE
J 0
(-5675 4900);
DISPLAY 0.872340 (-5675 4900);
DISPLAY INVISIBLE (-5675 4900);
FORCEPROP 1 LAST PATH I117
J 0
(-6002 5025);
DISPLAY 0.872340 (-6002 5025);
PAINT GREEN (-6002 5025);
DISPLAY INVISIBLE (-6002 5025);
FORCEADD TAP..1
(-6000 5075);
FORCEPROP 3 LASTPIN (-6050 5075) SIG_NAME M_K_CPU1_SA_DQ<26>
J 0
(-6040 5085);
DISPLAY 0.659574 (-6040 5085);
PAINT MONO (-6040 5085);
DISPLAY INVISIBLE (-6040 5085);
FORCEPROP 1 LASTPIN (-6050 5075) BN 26
J 0
(-6062 5083);
DISPLAY 0.489362 (-6062 5083);
PAINT GREEN (-6062 5083);
FORCEPROP 2 LAST CDS_LIB mstr_standard
J 0
(-6000 5075);
DISPLAY 0.723404 (-6000 5075);
PAINT MONO (-6000 5075);
DISPLAY INVISIBLE (-6000 5075);
FORCEPROP 1 LAST BODY_TYPE PLUMBING
J 0
(-6000 5125);
DISPLAY 0.872340 (-6000 5125);
PAINT GREEN (-6000 5125);
DISPLAY INVISIBLE (-6000 5125);
FORCEPROP 1 LAST HDL_TAP TRUE
J 0
(-5675 4950);
DISPLAY 0.872340 (-5675 4950);
DISPLAY INVISIBLE (-5675 4950);
FORCEPROP 1 LAST PATH I118
J 0
(-6002 5075);
DISPLAY 0.872340 (-6002 5075);
PAINT GREEN (-6002 5075);
DISPLAY INVISIBLE (-6002 5075);
FORCEADD TAP..1
(-6000 5125);
FORCEPROP 3 LASTPIN (-6050 5125) SIG_NAME M_K_CPU1_SA_DQ<27>
J 0
(-6040 5135);
DISPLAY 0.659574 (-6040 5135);
PAINT MONO (-6040 5135);
DISPLAY INVISIBLE (-6040 5135);
FORCEPROP 1 LASTPIN (-6050 5125) BN 27
J 0
(-6062 5133);
DISPLAY 0.489362 (-6062 5133);
PAINT GREEN (-6062 5133);
FORCEPROP 2 LAST CDS_LIB mstr_standard
J 0
(-6000 5125);
DISPLAY 0.723404 (-6000 5125);
PAINT MONO (-6000 5125);
DISPLAY INVISIBLE (-6000 5125);
FORCEPROP 1 LAST BODY_TYPE PLUMBING
J 0
(-6000 5175);
DISPLAY 0.872340 (-6000 5175);
PAINT GREEN (-6000 5175);
DISPLAY INVISIBLE (-6000 5175);
FORCEPROP 1 LAST HDL_TAP TRUE
J 0
(-5675 5000);
DISPLAY 0.872340 (-5675 5000);
DISPLAY INVISIBLE (-5675 5000);
FORCEPROP 1 LAST PATH I119
J 0
(-6002 5125);
DISPLAY 0.872340 (-6002 5125);
PAINT GREEN (-6002 5125);
DISPLAY INVISIBLE (-6002 5125);
FORCEADD OFFPAGE..1
(-8300 4025);
FORCEPROP 2 LAST $XR0 47 
J 0
(-8521 4025);
DISPLAY 0.638298 (-8521 4025);
PAINT MONO (-8521 4025);
FORCEPROP 2 LAST CDS_LIB mstr_standard
J 0
(-8300 4025);
DISPLAY 0.808511 (-8300 4025);
DISPLAY INVISIBLE (-8300 4025);
FORCEPROP 1 LAST OFFPAGE TRUE
J 0
(-7975 3900);
DISPLAY 0.872340 (-7975 3900);
PAINT GREEN (-7975 3900);
DISPLAY INVISIBLE (-7975 3900);
FORCEPROP 1 LAST COMMENT_BODY TRUE
J 0
(-8175 3925);
DISPLAY 0.872340 (-8175 3925);
PAINT GREEN (-8175 3925);
DISPLAY INVISIBLE (-8175 3925);
FORCEPROP 2 LAST PATH I12
J 0
(-8500 4075);
DISPLAY 1.021277 (-8500 4075);
DISPLAY INVISIBLE (-8500 4075);
FORCEADD TAP..1
(-6000 5175);
FORCEPROP 3 LASTPIN (-6050 5175) SIG_NAME M_K_CPU1_SA_DQ<28>
J 0
(-6040 5185);
DISPLAY 0.659574 (-6040 5185);
PAINT MONO (-6040 5185);
DISPLAY INVISIBLE (-6040 5185);
FORCEPROP 1 LASTPIN (-6050 5175) BN 28
J 0
(-6062 5183);
DISPLAY 0.489362 (-6062 5183);
PAINT GREEN (-6062 5183);
FORCEPROP 2 LAST CDS_LIB mstr_standard
J 0
(-6000 5175);
DISPLAY 0.723404 (-6000 5175);
PAINT MONO (-6000 5175);
DISPLAY INVISIBLE (-6000 5175);
FORCEPROP 1 LAST BODY_TYPE PLUMBING
J 0
(-6000 5225);
DISPLAY 0.872340 (-6000 5225);
PAINT GREEN (-6000 5225);
DISPLAY INVISIBLE (-6000 5225);
FORCEPROP 1 LAST HDL_TAP TRUE
J 0
(-5675 5050);
DISPLAY 0.872340 (-5675 5050);
DISPLAY INVISIBLE (-5675 5050);
FORCEPROP 1 LAST PATH I120
J 0
(-6002 5175);
DISPLAY 0.872340 (-6002 5175);
PAINT GREEN (-6002 5175);
DISPLAY INVISIBLE (-6002 5175);
FORCEADD TAP..1
(-6000 5275);
FORCEPROP 3 LASTPIN (-6050 5275) SIG_NAME M_K_CPU1_SA_DQ<30>
J 0
(-6040 5285);
DISPLAY 0.659574 (-6040 5285);
PAINT MONO (-6040 5285);
DISPLAY INVISIBLE (-6040 5285);
FORCEPROP 1 LASTPIN (-6050 5275) BN 30
J 0
(-6062 5283);
DISPLAY 0.489362 (-6062 5283);
PAINT GREEN (-6062 5283);
FORCEPROP 2 LAST CDS_LIB mstr_standard
J 0
(-6000 5275);
DISPLAY 0.723404 (-6000 5275);
PAINT MONO (-6000 5275);
DISPLAY INVISIBLE (-6000 5275);
FORCEPROP 1 LAST BODY_TYPE PLUMBING
J 0
(-6000 5325);
DISPLAY 0.872340 (-6000 5325);
PAINT GREEN (-6000 5325);
DISPLAY INVISIBLE (-6000 5325);
FORCEPROP 1 LAST HDL_TAP TRUE
J 0
(-5675 5150);
DISPLAY 0.872340 (-5675 5150);
DISPLAY INVISIBLE (-5675 5150);
FORCEPROP 1 LAST PATH I121
J 0
(-6002 5275);
DISPLAY 0.872340 (-6002 5275);
PAINT GREEN (-6002 5275);
DISPLAY INVISIBLE (-6002 5275);
FORCEADD TAP..1
(-6000 5325);
FORCEPROP 3 LASTPIN (-6050 5325) SIG_NAME M_K_CPU1_SA_DQ<31>
J 0
(-6040 5335);
DISPLAY 0.659574 (-6040 5335);
PAINT MONO (-6040 5335);
DISPLAY INVISIBLE (-6040 5335);
FORCEPROP 1 LASTPIN (-6050 5325) BN 31
J 0
(-6062 5333);
DISPLAY 0.489362 (-6062 5333);
PAINT GREEN (-6062 5333);
FORCEPROP 2 LAST CDS_LIB mstr_standard
J 0
(-6000 5325);
DISPLAY 0.723404 (-6000 5325);
PAINT MONO (-6000 5325);
DISPLAY INVISIBLE (-6000 5325);
FORCEPROP 1 LAST BODY_TYPE PLUMBING
J 0
(-6000 5375);
DISPLAY 0.872340 (-6000 5375);
PAINT GREEN (-6000 5375);
DISPLAY INVISIBLE (-6000 5375);
FORCEPROP 1 LAST HDL_TAP TRUE
J 0
(-5675 5200);
DISPLAY 0.872340 (-5675 5200);
DISPLAY INVISIBLE (-5675 5200);
FORCEPROP 1 LAST PATH I122
J 0
(-6002 5325);
DISPLAY 0.872340 (-6002 5325);
PAINT GREEN (-6002 5325);
DISPLAY INVISIBLE (-6002 5325);
FORCEADD TAP..1
(-6000 5225);
FORCEPROP 3 LASTPIN (-6050 5225) SIG_NAME M_K_CPU1_SA_DQ<29>
J 0
(-6040 5235);
DISPLAY 0.659574 (-6040 5235);
PAINT MONO (-6040 5235);
DISPLAY INVISIBLE (-6040 5235);
FORCEPROP 1 LASTPIN (-6050 5225) BN 29
J 0
(-6062 5233);
DISPLAY 0.489362 (-6062 5233);
PAINT GREEN (-6062 5233);
FORCEPROP 2 LAST CDS_LIB mstr_standard
J 0
(-6000 5225);
DISPLAY 0.723404 (-6000 5225);
PAINT MONO (-6000 5225);
DISPLAY INVISIBLE (-6000 5225);
FORCEPROP 1 LAST BODY_TYPE PLUMBING
J 0
(-6000 5275);
DISPLAY 0.872340 (-6000 5275);
PAINT GREEN (-6000 5275);
DISPLAY INVISIBLE (-6000 5275);
FORCEPROP 1 LAST HDL_TAP TRUE
J 0
(-5675 5100);
DISPLAY 0.872340 (-5675 5100);
DISPLAY INVISIBLE (-5675 5100);
FORCEPROP 1 LAST PATH I123
J 0
(-6002 5225);
DISPLAY 0.872340 (-6002 5225);
PAINT GREEN (-6002 5225);
DISPLAY INVISIBLE (-6002 5225);
FORCEADD OFFPAGE..3
(-5325 3725);
FORCEPROP 2 LAST $XR0 47 
J 0
(-5111 3725);
DISPLAY 0.638298 (-5111 3725);
PAINT MONO (-5111 3725);
FORCEPROP 2 LAST CDS_LIB mstr_standard
J 0
(-5325 3725);
DISPLAY 0.723404 (-5325 3725);
PAINT MONO (-5325 3725);
DISPLAY INVISIBLE (-5325 3725);
FORCEPROP 1 LAST OFFPAGE TRUE
J 0
(-5000 3600);
DISPLAY 0.872340 (-5000 3600);
PAINT GREEN (-5000 3600);
DISPLAY INVISIBLE (-5000 3600);
FORCEPROP 1 LAST COMMENT_BODY TRUE
J 0
(-5375 3625);
DISPLAY 0.872340 (-5375 3625);
PAINT GREEN (-5375 3625);
DISPLAY INVISIBLE (-5375 3625);
FORCEPROP 2 LAST PATH I124
J 0
(-5100 3775);
DISPLAY 1.021277 (-5100 3775);
DISPLAY INVISIBLE (-5100 3775);
FORCEADD OFFPAGE..3
(-5325 5375);
FORCEPROP 2 LAST $XR0 47 
J 0
(-5111 5375);
DISPLAY 0.638298 (-5111 5375);
PAINT MONO (-5111 5375);
FORCEPROP 2 LAST CDS_LIB mstr_standard
J 0
(-5325 5375);
DISPLAY 0.723404 (-5325 5375);
PAINT MONO (-5325 5375);
DISPLAY INVISIBLE (-5325 5375);
FORCEPROP 1 LAST OFFPAGE TRUE
J 0
(-5000 5250);
DISPLAY 0.872340 (-5000 5250);
PAINT GREEN (-5000 5250);
DISPLAY INVISIBLE (-5000 5250);
FORCEPROP 1 LAST COMMENT_BODY TRUE
J 0
(-5375 5275);
DISPLAY 0.872340 (-5375 5275);
PAINT GREEN (-5375 5275);
DISPLAY INVISIBLE (-5375 5275);
FORCEPROP 2 LAST PATH I125
J 0
(-5100 5425);
DISPLAY 1.021277 (-5100 5425);
DISPLAY INVISIBLE (-5100 5425);
FORCEADD GND..1
(-6400 875);
FORCEPROP 3 LASTPIN (-6400 925) SIG_NAME GND\g
J 0
(-6390 935);
DISPLAY 0.659574 (-6390 935);
PAINT MONO (-6390 935);
DISPLAY INVISIBLE (-6390 935);
FORCEPROP 2 LAST BOM_COST MEM
J 0
(-6500 950);
DISPLAY 0.808511 (-6500 950);
DISPLAY INVISIBLE (-6500 950);
FORCEPROP 1 LAST SIZE 1B
J 0
(-6325 825);
DISPLAY 0.851064 (-6325 825);
PAINT GREEN (-6325 825);
DISPLAY INVISIBLE (-6325 825);
FORCEPROP 2 LAST CDS_LIB mstr_symbols
J 0
(-6400 875);
DISPLAY 0.808511 (-6400 875);
DISPLAY INVISIBLE (-6400 875);
FORCEPROP 1 LAST VOLTAGE 0.0
J 0
(-6445 832);
DISPLAY 0.723404 (-6445 832);
PAINT SKYBLUE (-6445 832);
DISPLAY INVISIBLE (-6445 832);
FORCEPROP 1 LAST BODY_TYPE PLUMBING
J 0
(-6445 832);
DISPLAY 0.340426 (-6445 832);
PAINT GREEN (-6445 832);
DISPLAY INVISIBLE (-6445 832);
FORCEPROP 1 LAST HDL_POWER GND
J 0
(-6400 1025);
DISPLAY 0.851064 (-6400 1025);
PAINT GREEN (-6400 1025);
DISPLAY INVISIBLE (-6400 1025);
FORCEPROP 1 LAST PATH I126
J 0
(-6325 875);
DISPLAY 0.872340 (-6325 875);
PAINT AQUA (-6325 875);
DISPLAY INVISIBLE (-6325 875);
FORCEADD OFFPAGE..5
(-7175 1275);
FORCEPROP 2 LAST $XR0 108 
J 0
(-7460 1275);
DISPLAY 0.638298 (-7460 1275);
PAINT MONO (-7460 1275);
FORCEPROP 2 LAST CDS_LIB mstr_standard
J 0
(-7175 1275);
DISPLAY 0.808511 (-7175 1275);
DISPLAY INVISIBLE (-7175 1275);
FORCEPROP 2 LAST BOM_COST MEM
J 0
(-7250 1350);
DISPLAY 0.808511 (-7250 1350);
DISPLAY INVISIBLE (-7250 1350);
FORCEPROP 1 LAST OFFPAGE TRUE
J 0
(-6850 1150);
DISPLAY 0.872340 (-6850 1150);
PAINT GREEN (-6850 1150);
DISPLAY INVISIBLE (-6850 1150);
FORCEPROP 1 LAST COMMENT_BODY TRUE
J 0
(-7075 1200);
DISPLAY 0.872340 (-7075 1200);
PAINT GREEN (-7075 1200);
DISPLAY INVISIBLE (-7075 1200);
FORCEPROP 2 LAST PATH I127
J 0
(-7450 1325);
DISPLAY 1.021277 (-7450 1325);
DISPLAY INVISIBLE (-7450 1325);
FORCEADD OFFPAGE..6
(-8300 3975);
FORCEPROP 2 LAST $XR0 47 
J 0
(-8549 3975);
DISPLAY 0.638298 (-8549 3975);
PAINT MONO (-8549 3975);
FORCEPROP 2 LAST CDS_LIB mstr_standard
J 0
(-8300 3975);
DISPLAY 0.723404 (-8300 3975);
PAINT MONO (-8300 3975);
DISPLAY INVISIBLE (-8300 3975);
FORCEPROP 1 LAST OFFPAGE TRUE
J 0
(-7975 3850);
DISPLAY 0.872340 (-7975 3850);
PAINT GREEN (-7975 3850);
DISPLAY INVISIBLE (-7975 3850);
FORCEPROP 1 LAST COMMENT_BODY TRUE
J 0
(-8200 3900);
DISPLAY 0.872340 (-8200 3900);
PAINT GREEN (-8200 3900);
DISPLAY INVISIBLE (-8200 3900);
FORCEPROP 2 LAST PATH I13
J 0
(-8575 4025);
DISPLAY 1.021277 (-8575 4025);
DISPLAY INVISIBLE (-8575 4025);
FORCEADD Q_RES..2
(-6400 1100);
FORCEPROP 1 LAST LOCATION R777
J 0
(-6355 1225);
DISPLAY 0.489362 (-6355 1225);
PAINT SKYBLUE (-6355 1225);
FORCEPROP 0 LAST $SEC 1
J 0
(-6350 1275);
DISPLAY 0.680851 (-6350 1275);
PAINT MONO (-6350 1275);
DISPLAY INVISIBLE (-6350 1275);
FORCEPROP 0 LAST CDS_SEC 1
J 0
(-6350 1275);
DISPLAY 1.021277 (-6350 1275);
DISPLAY INVISIBLE (-6350 1275);
FORCEPROP 1 LASTPIN (-6400 1200) $PN 1
J 0
(-6395 1162);
DISPLAY 0.489362 (-6395 1162);
PAINT MONO (-6395 1162);
FORCEPROP 1 LASTPIN (-6400 1000) $PN 2
J 0
(-6395 1010);
DISPLAY 0.489362 (-6395 1010);
PAINT MONO (-6395 1010);
FORCEPROP 1 LAST PACK_TYPE 0402LF
J 0
(-6360 925);
DISPLAY 0.489362 (-6360 925);
PAINT SKYBLUE (-6360 925);
FORCEPROP 1 LAST VALUE 54.9K
J 0
(-6355 1175);
DISPLAY 0.489362 (-6355 1175);
PAINT SKYBLUE (-6355 1175);
FORCEPROP 1 LAST TOLERANCE 1%
J 0
(-6355 1125);
DISPLAY 0.489362 (-6355 1125);
PAINT SKYBLUE (-6355 1125);
FORCEPROP 1 LAST MATERIAL CHIP
J 0
(-6360 1025);
DISPLAY 0.489362 (-6360 1025);
PAINT SKYBLUE (-6360 1025);
FORCEPROP 1 LAST WATTAGE 1/16W
J 0
(-6360 1075);
DISPLAY 0.489362 (-6360 1075);
PAINT SKYBLUE (-6360 1075);
FORCEPROP 2 LAST CDS_LIB pure_quanta
J 0
(-6400 1100);
DISPLAY INVISIBLE (-6400 1100);
FORCEPROP 1 LAST PATH I136
J 0
(-6350 1275);
DISPLAY 0.978723 (-6350 1275);
PAINT WHITE (-6350 1275);
DISPLAY INVISIBLE (-6350 1275);
FORCEPROP 1 LAST PART_NUMBER CS35492FB03
J 0
(-6360 975);
DISPLAY 0.489362 (-6360 975);
PAINT SKYBLUE (-6360 975);
DISPLAY INVISIBLE (-6360 975);
FORCEADD GND..1
(-2150 1850);
FORCEPROP 3 LASTPIN (-2150 1900) SIG_NAME GND\g
J 0
(-2140 1910);
DISPLAY 0.659574 (-2140 1910);
PAINT MONO (-2140 1910);
DISPLAY INVISIBLE (-2140 1910);
FORCEPROP 2 LAST CDS_LIB mstr_symbols
J 0
(-2150 1850);
DISPLAY 0.723404 (-2150 1850);
DISPLAY INVISIBLE (-2150 1850);
FORCEPROP 1 LAST SIZE 1B
J 0
(-2075 1800);
DISPLAY 0.851064 (-2075 1800);
PAINT GREEN (-2075 1800);
DISPLAY INVISIBLE (-2075 1800);
FORCEPROP 1 LAST VOLTAGE 0.0
J 0
(-2195 1807);
DISPLAY 0.723404 (-2195 1807);
PAINT SKYBLUE (-2195 1807);
DISPLAY INVISIBLE (-2195 1807);
FORCEPROP 1 LAST BODY_TYPE PLUMBING
J 0
(-2195 1807);
DISPLAY 0.340426 (-2195 1807);
PAINT GREEN (-2195 1807);
DISPLAY INVISIBLE (-2195 1807);
FORCEPROP 1 LAST HDL_POWER GND
J 0
(-2150 2000);
DISPLAY 0.851064 (-2150 2000);
PAINT GREEN (-2150 2000);
DISPLAY INVISIBLE (-2150 2000);
FORCEPROP 1 LAST PATH I137
J 0
(-2075 1850);
DISPLAY 0.872340 (-2075 1850);
PAINT AQUA (-2075 1850);
DISPLAY INVISIBLE (-2075 1850);
FORCEADD GND..1
(-350 1625);
FORCEPROP 3 LASTPIN (-350 1675) SIG_NAME GND\g
J 0
(-340 1685);
DISPLAY 0.659574 (-340 1685);
PAINT MONO (-340 1685);
DISPLAY INVISIBLE (-340 1685);
FORCEPROP 2 LAST CDS_LIB mstr_symbols
J 0
(-350 1625);
DISPLAY 0.723404 (-350 1625);
DISPLAY INVISIBLE (-350 1625);
FORCEPROP 1 LAST SIZE 1B
J 0
(-275 1575);
DISPLAY 0.851064 (-275 1575);
PAINT GREEN (-275 1575);
DISPLAY INVISIBLE (-275 1575);
FORCEPROP 1 LAST VOLTAGE 0.0
J 0
(-395 1582);
DISPLAY 0.723404 (-395 1582);
PAINT SKYBLUE (-395 1582);
DISPLAY INVISIBLE (-395 1582);
FORCEPROP 1 LAST BODY_TYPE PLUMBING
J 0
(-395 1582);
DISPLAY 0.340426 (-395 1582);
PAINT GREEN (-395 1582);
DISPLAY INVISIBLE (-395 1582);
FORCEPROP 1 LAST HDL_POWER GND
J 0
(-350 1775);
DISPLAY 0.851064 (-350 1775);
PAINT GREEN (-350 1775);
DISPLAY INVISIBLE (-350 1775);
FORCEPROP 1 LAST PATH I138
J 0
(-275 1625);
DISPLAY 0.872340 (-275 1625);
PAINT AQUA (-275 1625);
DISPLAY INVISIBLE (-275 1625);
FORCEADD SCONN288_DDR506112002KQ..3
(-1250 3625);
FORCEPROP 1 LAST LOCATION J99
J 0
(-1700 5600);
DISPLAY 0.468085 (-1700 5600);
PAINT SKYBLUE (-1700 5600);
FORCEPROP 0 LAST $SEC 3
J 0
(-1700 5750);
DISPLAY 0.680851 (-1700 5750);
PAINT MONO (-1700 5750);
DISPLAY INVISIBLE (-1700 5750);
FORCEPROP 2 LAST CDS_SEC 3
J 0
(-1700 5750);
DISPLAY 1.021277 (-1700 5750);
DISPLAY INVISIBLE (-1700 5750);
FORCEPROP 0 LASTPIN (-650 2025) $PN G1
J 0
(-640 2035);
DISPLAY 0.680851 (-640 2035);
PAINT MONO (-640 2035);
FORCEPROP 0 LASTPIN (-650 1975) $PN G2
J 0
(-640 1985);
DISPLAY 0.680851 (-640 1985);
PAINT MONO (-640 1985);
FORCEPROP 0 LASTPIN (-650 1925) $PN G3
J 0
(-640 1935);
DISPLAY 0.680851 (-640 1935);
PAINT MONO (-640 1935);
FORCEPROP 0 LASTPIN (-1850 5175) $PN 1
J 2
(-1860 5185);
DISPLAY 0.680851 (-1860 5185);
PAINT MONO (-1860 5185);
FORCEPROP 0 LASTPIN (-1850 5225) $PN 145
J 2
(-1860 5235);
DISPLAY 0.680851 (-1860 5235);
PAINT MONO (-1860 5235);
FORCEPROP 0 LASTPIN (-1850 5275) $PN 146
J 2
(-1860 5285);
DISPLAY 0.680851 (-1860 5285);
PAINT MONO (-1860 5285);
FORCEPROP 0 LASTPIN (-650 2125) $PN 6
J 0
(-640 2135);
DISPLAY 0.680851 (-640 2135);
PAINT MONO (-640 2135);
FORCEPROP 0 LASTPIN (-650 2175) $PN 8
J 0
(-640 2185);
DISPLAY 0.680851 (-640 2185);
PAINT MONO (-640 2185);
FORCEPROP 0 LASTPIN (-650 2225) $PN 10
J 0
(-640 2235);
DISPLAY 0.680851 (-640 2235);
PAINT MONO (-640 2235);
FORCEPROP 0 LASTPIN (-650 2275) $PN 13
J 0
(-640 2285);
DISPLAY 0.680851 (-640 2285);
PAINT MONO (-640 2285);
FORCEPROP 0 LASTPIN (-650 2325) $PN 15
J 0
(-640 2335);
DISPLAY 0.680851 (-640 2335);
PAINT MONO (-640 2335);
FORCEPROP 0 LASTPIN (-650 2375) $PN 17
J 0
(-640 2385);
DISPLAY 0.680851 (-640 2385);
PAINT MONO (-640 2385);
FORCEPROP 0 LASTPIN (-650 2425) $PN 19
J 0
(-640 2435);
DISPLAY 0.680851 (-640 2435);
PAINT MONO (-640 2435);
FORCEPROP 0 LASTPIN (-650 2475) $PN 21
J 0
(-640 2485);
DISPLAY 0.680851 (-640 2485);
PAINT MONO (-640 2485);
FORCEPROP 0 LASTPIN (-650 2525) $PN 24
J 0
(-640 2535);
DISPLAY 0.680851 (-640 2535);
PAINT MONO (-640 2535);
FORCEPROP 0 LASTPIN (-650 2575) $PN 26
J 0
(-640 2585);
DISPLAY 0.680851 (-640 2585);
PAINT MONO (-640 2585);
FORCEPROP 0 LASTPIN (-650 2625) $PN 28
J 0
(-640 2635);
DISPLAY 0.680851 (-640 2635);
PAINT MONO (-640 2635);
FORCEPROP 0 LASTPIN (-650 2675) $PN 30
J 0
(-640 2685);
DISPLAY 0.680851 (-640 2685);
PAINT MONO (-640 2685);
FORCEPROP 0 LASTPIN (-650 2725) $PN 32
J 0
(-640 2735);
DISPLAY 0.680851 (-640 2735);
PAINT MONO (-640 2735);
FORCEPROP 0 LASTPIN (-650 2775) $PN 35
J 0
(-640 2785);
DISPLAY 0.680851 (-640 2785);
PAINT MONO (-640 2785);
FORCEPROP 0 LASTPIN (-650 2825) $PN 37
J 0
(-640 2835);
DISPLAY 0.680851 (-640 2835);
PAINT MONO (-640 2835);
FORCEPROP 0 LASTPIN (-650 2875) $PN 39
J 0
(-640 2885);
DISPLAY 0.680851 (-640 2885);
PAINT MONO (-640 2885);
FORCEPROP 0 LASTPIN (-650 2925) $PN 41
J 0
(-640 2935);
DISPLAY 0.680851 (-640 2935);
PAINT MONO (-640 2935);
FORCEPROP 0 LASTPIN (-650 2975) $PN 43
J 0
(-640 2985);
DISPLAY 0.680851 (-640 2985);
PAINT MONO (-640 2985);
FORCEPROP 0 LASTPIN (-650 3025) $PN 46
J 0
(-640 3035);
DISPLAY 0.680851 (-640 3035);
PAINT MONO (-640 3035);
FORCEPROP 0 LASTPIN (-650 3075) $PN 48
J 0
(-640 3085);
DISPLAY 0.680851 (-640 3085);
PAINT MONO (-640 3085);
FORCEPROP 0 LASTPIN (-650 3125) $PN 50
J 0
(-640 3135);
DISPLAY 0.680851 (-640 3135);
PAINT MONO (-640 3135);
FORCEPROP 0 LASTPIN (-650 3175) $PN 52
J 0
(-640 3185);
DISPLAY 0.680851 (-640 3185);
PAINT MONO (-640 3185);
FORCEPROP 0 LASTPIN (-650 3225) $PN 54
J 0
(-640 3235);
DISPLAY 0.680851 (-640 3235);
PAINT MONO (-640 3235);
FORCEPROP 0 LASTPIN (-650 3275) $PN 57
J 0
(-640 3285);
DISPLAY 0.680851 (-640 3285);
PAINT MONO (-640 3285);
FORCEPROP 0 LASTPIN (-650 3325) $PN 59
J 0
(-640 3335);
DISPLAY 0.680851 (-640 3335);
PAINT MONO (-640 3335);
FORCEPROP 0 LASTPIN (-650 3375) $PN 61
J 0
(-640 3385);
DISPLAY 0.680851 (-640 3385);
PAINT MONO (-640 3385);
FORCEPROP 0 LASTPIN (-650 3425) $PN 63
J 0
(-640 3435);
DISPLAY 0.680851 (-640 3435);
PAINT MONO (-640 3435);
FORCEPROP 0 LASTPIN (-650 3475) $PN 65
J 0
(-640 3485);
DISPLAY 0.680851 (-640 3485);
PAINT MONO (-640 3485);
FORCEPROP 0 LASTPIN (-650 3525) $PN 67
J 0
(-640 3535);
DISPLAY 0.680851 (-640 3535);
PAINT MONO (-640 3535);
FORCEPROP 0 LASTPIN (-650 3575) $PN 69
J 0
(-640 3585);
DISPLAY 0.680851 (-640 3585);
PAINT MONO (-640 3585);
FORCEPROP 0 LASTPIN (-650 3625) $PN 71
J 0
(-640 3635);
DISPLAY 0.680851 (-640 3635);
PAINT MONO (-640 3635);
FORCEPROP 0 LASTPIN (-650 3675) $PN 73
J 0
(-640 3685);
DISPLAY 0.680851 (-640 3685);
PAINT MONO (-640 3685);
FORCEPROP 0 LASTPIN (-650 3725) $PN 75
J 0
(-640 3735);
DISPLAY 0.680851 (-640 3735);
PAINT MONO (-640 3735);
FORCEPROP 0 LASTPIN (-650 3775) $PN 77
J 0
(-640 3785);
DISPLAY 0.680851 (-640 3785);
PAINT MONO (-640 3785);
FORCEPROP 0 LASTPIN (-650 3825) $PN 79
J 0
(-640 3835);
DISPLAY 0.680851 (-640 3835);
PAINT MONO (-640 3835);
FORCEPROP 0 LASTPIN (-650 3875) $PN 81
J 0
(-640 3885);
DISPLAY 0.680851 (-640 3885);
PAINT MONO (-640 3885);
FORCEPROP 0 LASTPIN (-650 3925) $PN 83
J 0
(-640 3935);
DISPLAY 0.680851 (-640 3935);
PAINT MONO (-640 3935);
FORCEPROP 0 LASTPIN (-650 3975) $PN 85
J 0
(-640 3985);
DISPLAY 0.680851 (-640 3985);
PAINT MONO (-640 3985);
FORCEPROP 0 LASTPIN (-650 4025) $PN 88
J 0
(-640 4035);
DISPLAY 0.680851 (-640 4035);
PAINT MONO (-640 4035);
FORCEPROP 0 LASTPIN (-650 4075) $PN 90
J 0
(-640 4085);
DISPLAY 0.680851 (-640 4085);
PAINT MONO (-640 4085);
FORCEPROP 0 LASTPIN (-650 4125) $PN 92
J 0
(-640 4135);
DISPLAY 0.680851 (-640 4135);
PAINT MONO (-640 4135);
FORCEPROP 0 LASTPIN (-650 4175) $PN 95
J 0
(-640 4185);
DISPLAY 0.680851 (-640 4185);
PAINT MONO (-640 4185);
FORCEPROP 0 LASTPIN (-650 4225) $PN 97
J 0
(-640 4235);
DISPLAY 0.680851 (-640 4235);
PAINT MONO (-640 4235);
FORCEPROP 0 LASTPIN (-650 4275) $PN 99
J 0
(-640 4285);
DISPLAY 0.680851 (-640 4285);
PAINT MONO (-640 4285);
FORCEPROP 0 LASTPIN (-650 4325) $PN 101
J 0
(-640 4335);
DISPLAY 0.680851 (-640 4335);
PAINT MONO (-640 4335);
FORCEPROP 0 LASTPIN (-650 4375) $PN 103
J 0
(-640 4385);
DISPLAY 0.680851 (-640 4385);
PAINT MONO (-640 4385);
FORCEPROP 0 LASTPIN (-650 4425) $PN 106
J 0
(-640 4435);
DISPLAY 0.680851 (-640 4435);
PAINT MONO (-640 4435);
FORCEPROP 0 LASTPIN (-650 4475) $PN 108
J 0
(-640 4485);
DISPLAY 0.680851 (-640 4485);
PAINT MONO (-640 4485);
FORCEPROP 0 LASTPIN (-650 4525) $PN 110
J 0
(-640 4535);
DISPLAY 0.680851 (-640 4535);
PAINT MONO (-640 4535);
FORCEPROP 0 LASTPIN (-650 4575) $PN 112
J 0
(-640 4585);
DISPLAY 0.680851 (-640 4585);
PAINT MONO (-640 4585);
FORCEPROP 0 LASTPIN (-650 4625) $PN 114
J 0
(-640 4635);
DISPLAY 0.680851 (-640 4635);
PAINT MONO (-640 4635);
FORCEPROP 0 LASTPIN (-650 4675) $PN 117
J 0
(-640 4685);
DISPLAY 0.680851 (-640 4685);
PAINT MONO (-640 4685);
FORCEPROP 0 LASTPIN (-650 4725) $PN 119
J 0
(-640 4735);
DISPLAY 0.680851 (-640 4735);
PAINT MONO (-640 4735);
FORCEPROP 0 LASTPIN (-650 4775) $PN 121
J 0
(-640 4785);
DISPLAY 0.680851 (-640 4785);
PAINT MONO (-640 4785);
FORCEPROP 0 LASTPIN (-650 4825) $PN 123
J 0
(-640 4835);
DISPLAY 0.680851 (-640 4835);
PAINT MONO (-640 4835);
FORCEPROP 0 LASTPIN (-650 4875) $PN 125
J 0
(-640 4885);
DISPLAY 0.680851 (-640 4885);
PAINT MONO (-640 4885);
FORCEPROP 0 LASTPIN (-650 4925) $PN 128
J 0
(-640 4935);
DISPLAY 0.680851 (-640 4935);
PAINT MONO (-640 4935);
FORCEPROP 0 LASTPIN (-650 4975) $PN 130
J 0
(-640 4985);
DISPLAY 0.680851 (-640 4985);
PAINT MONO (-640 4985);
FORCEPROP 0 LASTPIN (-650 5025) $PN 132
J 0
(-640 5035);
DISPLAY 0.680851 (-640 5035);
PAINT MONO (-640 5035);
FORCEPROP 0 LASTPIN (-650 5075) $PN 134
J 0
(-640 5085);
DISPLAY 0.680851 (-640 5085);
PAINT MONO (-640 5085);
FORCEPROP 0 LASTPIN (-650 5125) $PN 136
J 0
(-640 5135);
DISPLAY 0.680851 (-640 5135);
PAINT MONO (-640 5135);
FORCEPROP 0 LASTPIN (-650 5175) $PN 139
J 0
(-640 5185);
DISPLAY 0.680851 (-640 5185);
PAINT MONO (-640 5185);
FORCEPROP 0 LASTPIN (-650 5225) $PN 141
J 0
(-640 5235);
DISPLAY 0.680851 (-640 5235);
PAINT MONO (-640 5235);
FORCEPROP 0 LASTPIN (-650 5275) $PN 143
J 0
(-640 5285);
DISPLAY 0.680851 (-640 5285);
PAINT MONO (-640 5285);
FORCEPROP 0 LASTPIN (-1850 2025) $PN 151
J 2
(-1860 2035);
DISPLAY 0.680851 (-1860 2035);
PAINT MONO (-1860 2035);
FORCEPROP 0 LASTPIN (-1850 2075) $PN 153
J 2
(-1860 2085);
DISPLAY 0.680851 (-1860 2085);
PAINT MONO (-1860 2085);
FORCEPROP 0 LASTPIN (-1850 2125) $PN 155
J 2
(-1860 2135);
DISPLAY 0.680851 (-1860 2135);
PAINT MONO (-1860 2135);
FORCEPROP 0 LASTPIN (-1850 2175) $PN 158
J 2
(-1860 2185);
DISPLAY 0.680851 (-1860 2185);
PAINT MONO (-1860 2185);
FORCEPROP 0 LASTPIN (-1850 2225) $PN 160
J 2
(-1860 2235);
DISPLAY 0.680851 (-1860 2235);
PAINT MONO (-1860 2235);
FORCEPROP 0 LASTPIN (-1850 2275) $PN 162
J 2
(-1860 2285);
DISPLAY 0.680851 (-1860 2285);
PAINT MONO (-1860 2285);
FORCEPROP 0 LASTPIN (-1850 2325) $PN 164
J 2
(-1860 2335);
DISPLAY 0.680851 (-1860 2335);
PAINT MONO (-1860 2335);
FORCEPROP 0 LASTPIN (-1850 2375) $PN 166
J 2
(-1860 2385);
DISPLAY 0.680851 (-1860 2385);
PAINT MONO (-1860 2385);
FORCEPROP 0 LASTPIN (-1850 2425) $PN 169
J 2
(-1860 2435);
DISPLAY 0.680851 (-1860 2435);
PAINT MONO (-1860 2435);
FORCEPROP 0 LASTPIN (-1850 2475) $PN 171
J 2
(-1860 2485);
DISPLAY 0.680851 (-1860 2485);
PAINT MONO (-1860 2485);
FORCEPROP 0 LASTPIN (-1850 2525) $PN 173
J 2
(-1860 2535);
DISPLAY 0.680851 (-1860 2535);
PAINT MONO (-1860 2535);
FORCEPROP 0 LASTPIN (-1850 2575) $PN 175
J 2
(-1860 2585);
DISPLAY 0.680851 (-1860 2585);
PAINT MONO (-1860 2585);
FORCEPROP 0 LASTPIN (-1850 2625) $PN 177
J 2
(-1860 2635);
DISPLAY 0.680851 (-1860 2635);
PAINT MONO (-1860 2635);
FORCEPROP 0 LASTPIN (-1850 2675) $PN 180
J 2
(-1860 2685);
DISPLAY 0.680851 (-1860 2685);
PAINT MONO (-1860 2685);
FORCEPROP 0 LASTPIN (-1850 2725) $PN 182
J 2
(-1860 2735);
DISPLAY 0.680851 (-1860 2735);
PAINT MONO (-1860 2735);
FORCEPROP 0 LASTPIN (-1850 2775) $PN 184
J 2
(-1860 2785);
DISPLAY 0.680851 (-1860 2785);
PAINT MONO (-1860 2785);
FORCEPROP 0 LASTPIN (-1850 2825) $PN 186
J 2
(-1860 2835);
DISPLAY 0.680851 (-1860 2835);
PAINT MONO (-1860 2835);
FORCEPROP 0 LASTPIN (-1850 2875) $PN 188
J 2
(-1860 2885);
DISPLAY 0.680851 (-1860 2885);
PAINT MONO (-1860 2885);
FORCEPROP 0 LASTPIN (-1850 2925) $PN 191
J 2
(-1860 2935);
DISPLAY 0.680851 (-1860 2935);
PAINT MONO (-1860 2935);
FORCEPROP 0 LASTPIN (-1850 2975) $PN 193
J 2
(-1860 2985);
DISPLAY 0.680851 (-1860 2985);
PAINT MONO (-1860 2985);
FORCEPROP 0 LASTPIN (-1850 3025) $PN 195
J 2
(-1860 3035);
DISPLAY 0.680851 (-1860 3035);
PAINT MONO (-1860 3035);
FORCEPROP 0 LASTPIN (-1850 3075) $PN 197
J 2
(-1860 3085);
DISPLAY 0.680851 (-1860 3085);
PAINT MONO (-1860 3085);
FORCEPROP 0 LASTPIN (-1850 3125) $PN 199
J 2
(-1860 3135);
DISPLAY 0.680851 (-1860 3135);
PAINT MONO (-1860 3135);
FORCEPROP 0 LASTPIN (-1850 3175) $PN 202
J 2
(-1860 3185);
DISPLAY 0.680851 (-1860 3185);
PAINT MONO (-1860 3185);
FORCEPROP 0 LASTPIN (-1850 3225) $PN 204
J 2
(-1860 3235);
DISPLAY 0.680851 (-1860 3235);
PAINT MONO (-1860 3235);
FORCEPROP 0 LASTPIN (-1850 3275) $PN 206
J 2
(-1860 3285);
DISPLAY 0.680851 (-1860 3285);
PAINT MONO (-1860 3285);
FORCEPROP 0 LASTPIN (-1850 3325) $PN 208
J 2
(-1860 3335);
DISPLAY 0.680851 (-1860 3335);
PAINT MONO (-1860 3335);
FORCEPROP 0 LASTPIN (-1850 3375) $PN 210
J 2
(-1860 3385);
DISPLAY 0.680851 (-1860 3385);
PAINT MONO (-1860 3385);
FORCEPROP 0 LASTPIN (-1850 3425) $PN 212
J 2
(-1860 3435);
DISPLAY 0.680851 (-1860 3435);
PAINT MONO (-1860 3435);
FORCEPROP 0 LASTPIN (-1850 3475) $PN 214
J 2
(-1860 3485);
DISPLAY 0.680851 (-1860 3485);
PAINT MONO (-1860 3485);
FORCEPROP 0 LASTPIN (-1850 3525) $PN 216
J 2
(-1860 3535);
DISPLAY 0.680851 (-1860 3535);
PAINT MONO (-1860 3535);
FORCEPROP 0 LASTPIN (-1850 3575) $PN 219
J 2
(-1860 3585);
DISPLAY 0.680851 (-1860 3585);
PAINT MONO (-1860 3585);
FORCEPROP 0 LASTPIN (-1850 3625) $PN 222
J 2
(-1860 3635);
DISPLAY 0.680851 (-1860 3635);
PAINT MONO (-1860 3635);
FORCEPROP 0 LASTPIN (-1850 3675) $PN 224
J 2
(-1860 3685);
DISPLAY 0.680851 (-1860 3685);
PAINT MONO (-1860 3685);
FORCEPROP 0 LASTPIN (-1850 3725) $PN 226
J 2
(-1860 3735);
DISPLAY 0.680851 (-1860 3735);
PAINT MONO (-1860 3735);
FORCEPROP 0 LASTPIN (-1850 3775) $PN 228
J 2
(-1860 3785);
DISPLAY 0.680851 (-1860 3785);
PAINT MONO (-1860 3785);
FORCEPROP 0 LASTPIN (-1850 3825) $PN 230
J 2
(-1860 3835);
DISPLAY 0.680851 (-1860 3835);
PAINT MONO (-1860 3835);
FORCEPROP 0 LASTPIN (-1850 3875) $PN 233
J 2
(-1860 3885);
DISPLAY 0.680851 (-1860 3885);
PAINT MONO (-1860 3885);
FORCEPROP 0 LASTPIN (-1850 3925) $PN 235
J 2
(-1860 3935);
DISPLAY 0.680851 (-1860 3935);
PAINT MONO (-1860 3935);
FORCEPROP 0 LASTPIN (-1850 3975) $PN 237
J 2
(-1860 3985);
DISPLAY 0.680851 (-1860 3985);
PAINT MONO (-1860 3985);
FORCEPROP 0 LASTPIN (-1850 4025) $PN 240
J 2
(-1860 4035);
DISPLAY 0.680851 (-1860 4035);
PAINT MONO (-1860 4035);
FORCEPROP 0 LASTPIN (-1850 4075) $PN 242
J 2
(-1860 4085);
DISPLAY 0.680851 (-1860 4085);
PAINT MONO (-1860 4085);
FORCEPROP 0 LASTPIN (-1850 4125) $PN 244
J 2
(-1860 4135);
DISPLAY 0.680851 (-1860 4135);
PAINT MONO (-1860 4135);
FORCEPROP 0 LASTPIN (-1850 4175) $PN 246
J 2
(-1860 4185);
DISPLAY 0.680851 (-1860 4185);
PAINT MONO (-1860 4185);
FORCEPROP 0 LASTPIN (-1850 4225) $PN 248
J 2
(-1860 4235);
DISPLAY 0.680851 (-1860 4235);
PAINT MONO (-1860 4235);
FORCEPROP 0 LASTPIN (-1850 4275) $PN 251
J 2
(-1860 4285);
DISPLAY 0.680851 (-1860 4285);
PAINT MONO (-1860 4285);
FORCEPROP 0 LASTPIN (-1850 4325) $PN 253
J 2
(-1860 4335);
DISPLAY 0.680851 (-1860 4335);
PAINT MONO (-1860 4335);
FORCEPROP 0 LASTPIN (-1850 4375) $PN 255
J 2
(-1860 4385);
DISPLAY 0.680851 (-1860 4385);
PAINT MONO (-1860 4385);
FORCEPROP 0 LASTPIN (-1850 4425) $PN 257
J 2
(-1860 4435);
DISPLAY 0.680851 (-1860 4435);
PAINT MONO (-1860 4435);
FORCEPROP 0 LASTPIN (-1850 4475) $PN 259
J 2
(-1860 4485);
DISPLAY 0.680851 (-1860 4485);
PAINT MONO (-1860 4485);
FORCEPROP 0 LASTPIN (-1850 4525) $PN 262
J 2
(-1860 4535);
DISPLAY 0.680851 (-1860 4535);
PAINT MONO (-1860 4535);
FORCEPROP 0 LASTPIN (-1850 4575) $PN 264
J 2
(-1860 4585);
DISPLAY 0.680851 (-1860 4585);
PAINT MONO (-1860 4585);
FORCEPROP 0 LASTPIN (-1850 4625) $PN 266
J 2
(-1860 4635);
DISPLAY 0.680851 (-1860 4635);
PAINT MONO (-1860 4635);
FORCEPROP 0 LASTPIN (-1850 4675) $PN 268
J 2
(-1860 4685);
DISPLAY 0.680851 (-1860 4685);
PAINT MONO (-1860 4685);
FORCEPROP 0 LASTPIN (-1850 4725) $PN 270
J 2
(-1860 4735);
DISPLAY 0.680851 (-1860 4735);
PAINT MONO (-1860 4735);
FORCEPROP 0 LASTPIN (-1850 4775) $PN 273
J 2
(-1860 4785);
DISPLAY 0.680851 (-1860 4785);
PAINT MONO (-1860 4785);
FORCEPROP 0 LASTPIN (-1850 4825) $PN 275
J 2
(-1860 4835);
DISPLAY 0.680851 (-1860 4835);
PAINT MONO (-1860 4835);
FORCEPROP 0 LASTPIN (-1850 4875) $PN 277
J 2
(-1860 4885);
DISPLAY 0.680851 (-1860 4885);
PAINT MONO (-1860 4885);
FORCEPROP 0 LASTPIN (-1850 4925) $PN 279
J 2
(-1860 4935);
DISPLAY 0.680851 (-1860 4935);
PAINT MONO (-1860 4935);
FORCEPROP 0 LASTPIN (-1850 4975) $PN 281
J 2
(-1860 4985);
DISPLAY 0.680851 (-1860 4985);
PAINT MONO (-1860 4985);
FORCEPROP 0 LASTPIN (-1850 5025) $PN 284
J 2
(-1860 5035);
DISPLAY 0.680851 (-1860 5035);
PAINT MONO (-1860 5035);
FORCEPROP 0 LASTPIN (-1850 5075) $PN 286
J 2
(-1860 5085);
DISPLAY 0.680851 (-1860 5085);
PAINT MONO (-1860 5085);
FORCEPROP 0 LASTPIN (-1850 5125) $PN 288
J 2
(-1860 5135);
DISPLAY 0.680851 (-1860 5135);
PAINT MONO (-1860 5135);
FORCEPROP 2 LAST VALUE SCONN288_DDR506112002KQ
J 0
(-1700 5650);
DISPLAY 0.489362 (-1700 5650);
PAINT SKYBLUE (-1700 5650);
FORCEPROP 2 LAST PART_TYPE SMLF
J 0
(-1700 5700);
DISPLAY 1.021277 (-1700 5700);
FORCEPROP 1 LAST MATERIAL IO
J 0
(-1700 5450);
DISPLAY 0.468085 (-1700 5450);
PAINT SKYBLUE (-1700 5450);
FORCEPROP 1 LAST CDS_LMAN_SYM_OUTLINE -450,1800,450,-1750
J 0
(-1250 3625);
DISPLAY 0.468085 (-1250 3625);
PAINT GREEN (-1250 3625);
DISPLAY INVISIBLE (-1250 3625);
FORCEPROP 1 LAST NEEDS_NO_SIZE TRUE
J 0
(-1250 3625);
DISPLAY 0.723404 (-1250 3625);
PAINT GREEN (-1250 3625);
DISPLAY INVISIBLE (-1250 3625);
FORCEPROP 2 LAST CDS_LIB pure_quanta
J 0
(-1250 3625);
DISPLAY INVISIBLE (-1250 3625);
FORCEPROP 1 LAST PATH I139
J 0
(-1250 3625);
DISPLAY 0.723404 (-1250 3625);
PAINT GREEN (-1250 3625);
DISPLAY INVISIBLE (-1250 3625);
FORCEPROP 1 LAST PART_NUMBER DFHST8FS479
J 0
(-1700 5525);
DISPLAY 0.468085 (-1700 5525);
PAINT SKYBLUE (-1700 5525);
DISPLAY INVISIBLE (-1700 5525);
FORCEADD OFFPAGE..1
(-8300 4175);
FORCEPROP 2 LAST $XR0 47 
J 0
(-8521 4175);
DISPLAY 0.638298 (-8521 4175);
PAINT MONO (-8521 4175);
FORCEPROP 2 LAST CDS_LIB mstr_standard
J 0
(-8300 4175);
DISPLAY 0.808511 (-8300 4175);
DISPLAY INVISIBLE (-8300 4175);
FORCEPROP 1 LAST OFFPAGE TRUE
J 0
(-7975 4050);
DISPLAY 0.872340 (-7975 4050);
PAINT GREEN (-7975 4050);
DISPLAY INVISIBLE (-7975 4050);
FORCEPROP 1 LAST COMMENT_BODY TRUE
J 0
(-8175 4075);
DISPLAY 0.872340 (-8175 4075);
PAINT GREEN (-8175 4075);
DISPLAY INVISIBLE (-8175 4075);
FORCEPROP 2 LAST PATH I14
J 0
(-8500 4225);
DISPLAY 1.021277 (-8500 4225);
DISPLAY INVISIBLE (-8500 4225);
FORCEADD OFFPAGE..1
(-8300 4225);
FORCEPROP 2 LAST $XR0 47 
J 0
(-8521 4225);
DISPLAY 0.638298 (-8521 4225);
PAINT MONO (-8521 4225);
FORCEPROP 2 LAST CDS_LIB mstr_standard
J 0
(-8300 4225);
DISPLAY 0.723404 (-8300 4225);
PAINT MONO (-8300 4225);
DISPLAY INVISIBLE (-8300 4225);
FORCEPROP 1 LAST OFFPAGE TRUE
J 0
(-7975 4100);
DISPLAY 0.872340 (-7975 4100);
PAINT GREEN (-7975 4100);
DISPLAY INVISIBLE (-7975 4100);
FORCEPROP 1 LAST COMMENT_BODY TRUE
J 0
(-8175 4125);
DISPLAY 0.872340 (-8175 4125);
PAINT GREEN (-8175 4125);
DISPLAY INVISIBLE (-8175 4125);
FORCEPROP 2 LAST PATH I15
J 0
(-8500 4275);
DISPLAY 1.021277 (-8500 4275);
DISPLAY INVISIBLE (-8500 4275);
FORCEADD OFFPAGE..1
(-8300 4375);
FORCEPROP 2 LAST $XR0 47 
J 0
(-8521 4375);
DISPLAY 0.638298 (-8521 4375);
PAINT MONO (-8521 4375);
FORCEPROP 2 LAST CDS_LIB mstr_standard
J 0
(-8300 4375);
DISPLAY 0.723404 (-8300 4375);
PAINT MONO (-8300 4375);
DISPLAY INVISIBLE (-8300 4375);
FORCEPROP 1 LAST OFFPAGE TRUE
J 0
(-7975 4250);
DISPLAY 0.872340 (-7975 4250);
PAINT GREEN (-7975 4250);
DISPLAY INVISIBLE (-7975 4250);
FORCEPROP 1 LAST COMMENT_BODY TRUE
J 0
(-8175 4275);
DISPLAY 0.872340 (-8175 4275);
PAINT GREEN (-8175 4275);
DISPLAY INVISIBLE (-8175 4275);
FORCEPROP 2 LAST PATH I16
J 0
(-8500 4425);
DISPLAY 1.021277 (-8500 4425);
DISPLAY INVISIBLE (-8500 4425);
FORCEADD OFFPAGE..1
(-8300 4325);
FORCEPROP 2 LAST $XR0 47 
J 0
(-8521 4325);
DISPLAY 0.638298 (-8521 4325);
PAINT MONO (-8521 4325);
FORCEPROP 2 LAST CDS_LIB mstr_standard
J 0
(-8300 4325);
DISPLAY 0.808511 (-8300 4325);
DISPLAY INVISIBLE (-8300 4325);
FORCEPROP 1 LAST OFFPAGE TRUE
J 0
(-7975 4200);
DISPLAY 0.872340 (-7975 4200);
PAINT GREEN (-7975 4200);
DISPLAY INVISIBLE (-7975 4200);
FORCEPROP 1 LAST COMMENT_BODY TRUE
J 0
(-8175 4225);
DISPLAY 0.872340 (-8175 4225);
PAINT GREEN (-8175 4225);
DISPLAY INVISIBLE (-8175 4225);
FORCEPROP 2 LAST PATH I17
J 0
(-8500 4375);
DISPLAY 1.021277 (-8500 4375);
DISPLAY INVISIBLE (-8500 4375);
FORCEADD OFFPAGE..1
(-8300 4525);
FORCEPROP 2 LAST $XR0 47 
J 0
(-8521 4525);
DISPLAY 0.638298 (-8521 4525);
PAINT MONO (-8521 4525);
FORCEPROP 2 LAST CDS_LIB mstr_standard
J 0
(-8300 4525);
DISPLAY 0.723404 (-8300 4525);
PAINT MONO (-8300 4525);
DISPLAY INVISIBLE (-8300 4525);
FORCEPROP 1 LAST OFFPAGE TRUE
J 0
(-7975 4400);
DISPLAY 0.872340 (-7975 4400);
PAINT GREEN (-7975 4400);
DISPLAY INVISIBLE (-7975 4400);
FORCEPROP 1 LAST COMMENT_BODY TRUE
J 0
(-8175 4425);
DISPLAY 0.872340 (-8175 4425);
PAINT GREEN (-8175 4425);
DISPLAY INVISIBLE (-8175 4425);
FORCEPROP 2 LAST PATH I18
J 0
(-8500 4575);
DISPLAY 1.021277 (-8500 4575);
DISPLAY INVISIBLE (-8500 4575);
FORCEADD Q_CAP..1
R 2
(-8675 3150);
FORCEPROP 1 LAST LOCATION C176
J 2
(-8725 3250);
DISPLAY 0.489362 (-8725 3250);
PAINT SKYBLUE (-8725 3250);
FORCEPROP 0 LAST $SEC 1
J 0
(-8725 3300);
DISPLAY 0.680851 (-8725 3300);
PAINT MONO (-8725 3300);
DISPLAY INVISIBLE (-8725 3300);
FORCEPROP 0 LAST CDS_SEC 1
J 0
(-8725 3300);
DISPLAY 1.021277 (-8725 3300);
DISPLAY INVISIBLE (-8725 3300);
FORCEPROP 1 LASTPIN (-8675 3250) $PN 1
J 2
(-8685 3230);
DISPLAY 0.489362 (-8685 3230);
PAINT MONO (-8685 3230);
FORCEPROP 1 LASTPIN (-8675 3050) $PN 2
J 2
(-8685 3030);
DISPLAY 0.489362 (-8685 3030);
PAINT MONO (-8685 3030);
FORCEPROP 1 LAST VALUE 0.1UF
J 2
(-8725 3200);
DISPLAY 0.489362 (-8725 3200);
PAINT SKYBLUE (-8725 3200);
FORCEPROP 1 LAST VOLTAGE 25V
J 2
(-8725 3150);
DISPLAY 0.489362 (-8725 3150);
PAINT SKYBLUE (-8725 3150);
FORCEPROP 1 LAST MATERIAL X7R
J 2
(-8725 3050);
DISPLAY 0.489362 (-8725 3050);
PAINT SKYBLUE (-8725 3050);
FORCEPROP 1 LAST PACK_TYPE 0402
J 2
(-8725 2950);
DISPLAY 0.489362 (-8725 2950);
PAINT SKYBLUE (-8725 2950);
FORCEPROP 1 LAST TOLERANCE 10%
J 2
(-8725 3100);
DISPLAY 0.489362 (-8725 3100);
PAINT SKYBLUE (-8725 3100);
FORCEPROP 0 LAST BOM_COST MEM
J 2
(-8730 3295);
DISPLAY 0.595745 (-8730 3295);
PAINT MONO (-8730 3295);
DISPLAY INVISIBLE (-8730 3295);
FORCEPROP 2 LAST CDS_LIB pure_quanta
J 0
(-8675 3150);
DISPLAY INVISIBLE (-8675 3150);
FORCEPROP 2 LAST ROOM 
J 2
(-8730 3295);
DISPLAY 0.595745 (-8730 3295);
PAINT RED (-8730 3295);
DISPLAY INVISIBLE (-8730 3295);
FORCEPROP 1 LAST PATH I185
J 2
(-8725 3300);
DISPLAY 0.978723 (-8725 3300);
PAINT WHITE (-8725 3300);
DISPLAY INVISIBLE (-8725 3300);
FORCEPROP 1 LAST PART_NUMBER CH4104K1B00
J 2
(-8725 3000);
DISPLAY 0.489362 (-8725 3000);
PAINT SKYBLUE (-8725 3000);
DISPLAY INVISIBLE (-8725 3000);
FORCEADD GND..1
(-8675 2925);
FORCEPROP 3 LASTPIN (-8675 2975) SIG_NAME GND\g
J 0
(-8665 2985);
DISPLAY 0.659574 (-8665 2985);
PAINT MONO (-8665 2985);
DISPLAY INVISIBLE (-8665 2985);
FORCEPROP 2 LAST CDS_LIB mstr_symbols
J 0
(-8675 2925);
DISPLAY 0.808511 (-8675 2925);
DISPLAY INVISIBLE (-8675 2925);
FORCEPROP 1 LAST SIZE 1B
J 0
(-8600 2875);
DISPLAY 0.723404 (-8600 2875);
PAINT GREEN (-8600 2875);
DISPLAY INVISIBLE (-8600 2875);
FORCEPROP 2 LAST BOM_COST MEM
J 0
(-8650 3050);
DISPLAY 0.659574 (-8650 3050);
DISPLAY INVISIBLE (-8650 3050);
FORCEPROP 1 LAST VOLTAGE 0
J 0
(-8695 3020);
DISPLAY 0.829787 (-8695 3020);
PAINT SKYBLUE (-8695 3020);
DISPLAY INVISIBLE (-8695 3020);
FORCEPROP 2 LAST ROOM MEM_EFGH_DECOUPLING_CAPS
J 0
(-8650 3000);
DISPLAY 0.659574 (-8650 3000);
PAINT RED (-8650 3000);
DISPLAY INVISIBLE (-8650 3000);
FORCEPROP 1 LAST BODY_TYPE PLUMBING
J 0
(-8720 2882);
DISPLAY 0.276596 (-8720 2882);
PAINT GREEN (-8720 2882);
DISPLAY INVISIBLE (-8720 2882);
FORCEPROP 1 LAST HDL_POWER GND
J 0
(-8675 3075);
DISPLAY 0.723404 (-8675 3075);
PAINT GREEN (-8675 3075);
DISPLAY INVISIBLE (-8675 3075);
FORCEPROP 1 LAST PATH I186
J 0
(-8600 2925);
DISPLAY 0.872340 (-8600 2925);
PAINT AQUA (-8600 2925);
DISPLAY INVISIBLE (-8600 2925);
FORCEADD OFFPAGE..6
(-9025 2075);
FORCEPROP 2 LAST $XR4 109 
J 0
(-9305 2147);
DISPLAY 0.638298 (-9305 2147);
PAINT MONO (-9305 2147);
FORCEPROP 2 LAST $XR3 107 
J 0
(-9305 2003);
DISPLAY 0.638298 (-9305 2003);
PAINT MONO (-9305 2003);
FORCEPROP 2 LAST $XR2 106 
J 0
(-9305 2111);
DISPLAY 0.638298 (-9305 2111);
PAINT MONO (-9305 2111);
FORCEPROP 2 LAST $XR1 105 
J 0
(-9305 2039);
DISPLAY 0.638298 (-9305 2039);
PAINT MONO (-9305 2039);
FORCEPROP 2 LAST $XR0 104 
J 0
(-9305 2075);
DISPLAY 0.638298 (-9305 2075);
PAINT MONO (-9305 2075);
FORCEPROP 2 LAST CDS_LIB mstr_standard
J 0
(-9025 2075);
DISPLAY INVISIBLE (-9025 2075);
FORCEPROP 1 LAST OFFPAGE TRUE
J 0
(-8700 1950);
DISPLAY 0.872340 (-8700 1950);
PAINT GREEN (-8700 1950);
DISPLAY INVISIBLE (-8700 1950);
FORCEPROP 1 LAST COMMENT_BODY TRUE
J 0
(-8925 2000);
DISPLAY 0.872340 (-8925 2000);
PAINT GREEN (-8925 2000);
DISPLAY INVISIBLE (-8925 2000);
FORCEPROP 2 LAST PATH I187
J 0
(-8975 2150);
DISPLAY 1.021277 (-8975 2150);
DISPLAY INVISIBLE (-8975 2150);
FORCEADD Q_RES..1
R 2
(-8500 2075);
FORCEPROP 1 LAST LOCATION R313
J 2
(-8450 2125);
DISPLAY 0.489362 (-8450 2125);
PAINT SKYBLUE (-8450 2125);
FORCEPROP 0 LAST $SEC 1
J 0
(-8450 2175);
DISPLAY 0.680851 (-8450 2175);
PAINT MONO (-8450 2175);
DISPLAY INVISIBLE (-8450 2175);
FORCEPROP 0 LAST CDS_SEC 1
J 0
(-8450 2175);
DISPLAY 1.021277 (-8450 2175);
DISPLAY INVISIBLE (-8450 2175);
FORCEPROP 1 LASTPIN (-8400 2075) $PN 1
J 2
(-8412 2087);
DISPLAY 0.489362 (-8412 2087);
PAINT MONO (-8412 2087);
FORCEPROP 1 LASTPIN (-8600 2075) $PN 2
J 2
(-8562 2087);
DISPLAY 0.489362 (-8562 2087);
PAINT MONO (-8562 2087);
FORCEPROP 1 LAST VALUE 1K
J 0
(-8500 2025);
DISPLAY 0.489362 (-8500 2025);
PAINT SKYBLUE (-8500 2025);
FORCEPROP 1 LAST TOLERANCE 1%
J 2
(-8375 2050);
DISPLAY 0.489362 (-8375 2050);
PAINT SKYBLUE (-8375 2050);
DISPLAY INVISIBLE (-8375 2050);
FORCEPROP 2 LAST CDS_LIB pure_quanta
J 0
(-8500 2075);
DISPLAY INVISIBLE (-8500 2075);
FORCEPROP 2 LAST BOM_COST MEM
J 0
(-8525 2225);
DISPLAY 0.744681 (-8525 2225);
PAINT WHITE (-8525 2225);
DISPLAY INVISIBLE (-8525 2225);
FORCEPROP 1 LAST WATTAGE 1/16W
J 0
(-8425 2000);
DISPLAY 0.489362 (-8425 2000);
PAINT SKYBLUE (-8425 2000);
DISPLAY INVISIBLE (-8425 2000);
FORCEPROP 1 LAST MATERIAL CHIP
J 0
(-8675 2050);
DISPLAY 0.489362 (-8675 2050);
PAINT SKYBLUE (-8675 2050);
DISPLAY INVISIBLE (-8675 2050);
FORCEPROP 1 LAST PACK_TYPE 0402LF
J 0
(-8675 2000);
DISPLAY 0.489362 (-8675 2000);
PAINT SKYBLUE (-8675 2000);
DISPLAY INVISIBLE (-8675 2000);
FORCEPROP 2 LAST ROOM 
J 0
(-8525 2175);
DISPLAY 0.744681 (-8525 2175);
PAINT RED (-8525 2175);
DISPLAY INVISIBLE (-8525 2175);
FORCEPROP 1 LAST PATH I188
J 2
(-8450 2225);
DISPLAY 0.978723 (-8450 2225);
PAINT WHITE (-8450 2225);
DISPLAY INVISIBLE (-8450 2225);
FORCEPROP 1 LAST PART_NUMBER CS21002FB06
J 0
(-8600 2125);
DISPLAY 0.489362 (-8600 2125);
PAINT SKYBLUE (-8600 2125);
DISPLAY INVISIBLE (-8600 2125);
FORCEADD VCC_CORE..1
(-8375 2400);
FORCEPROP 3 LASTPIN (-8375 2350) SIG_NAME P3V3\g
J 0
(-8365 2360);
DISPLAY 0.659574 (-8365 2360);
PAINT MONO (-8365 2360);
DISPLAY INVISIBLE (-8365 2360);
FORCEPROP 1 LAST HDL_POWER P3V3
J 1
(-8375 2450);
DISPLAY 0.489362 (-8375 2450);
PAINT GREEN (-8375 2450);
FORCEPROP 2 LAST CDS_LIB mstr_symbols
J 0
(-8375 2400);
DISPLAY INVISIBLE (-8375 2400);
FORCEPROP 0 LAST VOLTAGE 3.3
J 0
(-8650 2550);
DISPLAY 1.021277 (-8650 2550);
PAINT SKYBLUE (-8650 2550);
DISPLAY INVISIBLE (-8650 2550);
FORCEPROP 2 LAST ROOM PVCCINFAON_CPU0_CTRL
J 0
(-8375 2500);
DISPLAY 0.808511 (-8375 2500);
PAINT RED (-8375 2500);
DISPLAY INVISIBLE (-8375 2500);
FORCEPROP 1 LAST PATH I189
J 0
(-8325 2425);
DISPLAY 0.872340 (-8325 2425);
PAINT AQUA (-8325 2425);
DISPLAY INVISIBLE (-8325 2425);
FORCEADD OFFPAGE..1
(-8300 4475);
FORCEPROP 2 LAST $XR0 47 
J 0
(-8521 4475);
DISPLAY 0.638298 (-8521 4475);
PAINT MONO (-8521 4475);
FORCEPROP 2 LAST CDS_LIB mstr_standard
J 0
(-8300 4475);
DISPLAY 0.808511 (-8300 4475);
DISPLAY INVISIBLE (-8300 4475);
FORCEPROP 1 LAST OFFPAGE TRUE
J 0
(-7975 4350);
DISPLAY 0.872340 (-7975 4350);
PAINT GREEN (-7975 4350);
DISPLAY INVISIBLE (-7975 4350);
FORCEPROP 1 LAST COMMENT_BODY TRUE
J 0
(-8175 4375);
DISPLAY 0.872340 (-8175 4375);
PAINT GREEN (-8175 4375);
DISPLAY INVISIBLE (-8175 4375);
FORCEPROP 2 LAST PATH I19
J 0
(-8500 4525);
DISPLAY 1.021277 (-8500 4525);
DISPLAY INVISIBLE (-8500 4525);
FORCEADD Q_RES..2
(-8375 2225);
FORCEPROP 1 LAST LOCATION R114
J 0
(-8330 2350);
DISPLAY 0.489362 (-8330 2350);
PAINT SKYBLUE (-8330 2350);
FORCEPROP 0 LAST $SEC 1
J 0
(-8325 2400);
DISPLAY 0.680851 (-8325 2400);
PAINT MONO (-8325 2400);
DISPLAY INVISIBLE (-8325 2400);
FORCEPROP 0 LAST CDS_SEC 1
J 0
(-8325 2400);
DISPLAY 1.021277 (-8325 2400);
DISPLAY INVISIBLE (-8325 2400);
FORCEPROP 1 LASTPIN (-8375 2325) $PN 1
J 0
(-8370 2287);
DISPLAY 0.489362 (-8370 2287);
PAINT MONO (-8370 2287);
FORCEPROP 1 LASTPIN (-8375 2125) $PN 2
J 0
(-8370 2135);
DISPLAY 0.489362 (-8370 2135);
PAINT MONO (-8370 2135);
FORCEPROP 1 LAST TOLERANCE 1%
J 0
(-8325 2275);
DISPLAY 0.489362 (-8325 2275);
PAINT SKYBLUE (-8325 2275);
FORCEPROP 1 LAST WATTAGE 1/16W
J 0
(-8325 2250);
DISPLAY 0.489362 (-8325 2250);
PAINT SKYBLUE (-8325 2250);
FORCEPROP 1 LAST MATERIAL EMPTY
J 0
(-8325 2225);
DISPLAY 0.489362 (-8325 2225);
PAINT RED (-8325 2225);
FORCEPROP 1 LAST PACK_TYPE 0402LF
J 0
(-8325 2175);
DISPLAY 0.489362 (-8325 2175);
PAINT SKYBLUE (-8325 2175);
FORCEPROP 1 LAST VALUE 1K
J 0
(-8330 2300);
DISPLAY 0.489362 (-8330 2300);
PAINT SKYBLUE (-8330 2300);
FORCEPROP 2 LAST CDS_LIB pure_quanta
J 0
(-8375 2225);
DISPLAY INVISIBLE (-8375 2225);
FORCEPROP 2 LAST BOM_COST MEM
J 0
(-8325 2400);
DISPLAY 0.808511 (-8325 2400);
DISPLAY INVISIBLE (-8325 2400);
FORCEPROP 2 LAST ROOM 
J 0
(-8325 2450);
DISPLAY 0.808511 (-8325 2450);
PAINT RED (-8325 2450);
DISPLAY INVISIBLE (-8325 2450);
FORCEPROP 1 LAST PATH I190
J 0
(-8325 2400);
DISPLAY 0.978723 (-8325 2400);
PAINT WHITE (-8325 2400);
DISPLAY INVISIBLE (-8325 2400);
FORCEPROP 1 LAST PART_NUMBER CS21002FB06
J 0
(-8325 2200);
DISPLAY 0.489362 (-8325 2200);
PAINT SKYBLUE (-8325 2200);
DISPLAY INVISIBLE (-8325 2200);
FORCEADD OFFPAGE..2
(-2475 4550);
FORCEPROP 2 LAST $XR0 47 
J 0
(-2286 4550);
DISPLAY 0.638298 (-2286 4550);
PAINT MONO (-2286 4550);
FORCEPROP 2 LAST CDS_LIB mstr_standard
J 0
(-2475 4550);
DISPLAY 0.723404 (-2475 4550);
PAINT MONO (-2475 4550);
DISPLAY INVISIBLE (-2475 4550);
FORCEPROP 1 LAST OFFPAGE TRUE
J 0
(-2150 4425);
DISPLAY 0.723404 (-2150 4425);
PAINT GREEN (-2150 4425);
DISPLAY INVISIBLE (-2150 4425);
FORCEPROP 1 LAST COMMENT_BODY TRUE
J 0
(-2520 4455);
DISPLAY 0.872340 (-2520 4455);
PAINT GREEN (-2520 4455);
DISPLAY INVISIBLE (-2520 4455);
FORCEPROP 2 LAST PATH I191
J 0
(-2275 4600);
DISPLAY 0.680851 (-2275 4600);
DISPLAY INVISIBLE (-2275 4600);
FORCEADD OFFPAGE..2
(-2475 4500);
FORCEPROP 2 LAST $XR0 47 
J 0
(-2286 4500);
DISPLAY 0.638298 (-2286 4500);
PAINT MONO (-2286 4500);
FORCEPROP 2 LAST CDS_LIB mstr_standard
J 0
(-2475 4500);
DISPLAY 0.723404 (-2475 4500);
PAINT MONO (-2475 4500);
DISPLAY INVISIBLE (-2475 4500);
FORCEPROP 1 LAST OFFPAGE TRUE
J 0
(-2150 4375);
DISPLAY 0.723404 (-2150 4375);
PAINT GREEN (-2150 4375);
DISPLAY INVISIBLE (-2150 4375);
FORCEPROP 1 LAST COMMENT_BODY TRUE
J 0
(-2520 4405);
DISPLAY 0.872340 (-2520 4405);
PAINT GREEN (-2520 4405);
DISPLAY INVISIBLE (-2520 4405);
FORCEPROP 2 LAST PATH I192
J 0
(-2275 4550);
DISPLAY 0.680851 (-2275 4550);
DISPLAY INVISIBLE (-2275 4550);
FORCEADD OFFPAGE..2
(-2475 3500);
FORCEPROP 2 LAST $XR0 47 
J 0
(-2286 3500);
DISPLAY 0.638298 (-2286 3500);
PAINT MONO (-2286 3500);
FORCEPROP 2 LAST CDS_LIB mstr_standard
J 0
(-2475 3500);
DISPLAY 0.723404 (-2475 3500);
PAINT MONO (-2475 3500);
DISPLAY INVISIBLE (-2475 3500);
FORCEPROP 1 LAST OFFPAGE TRUE
J 0
(-2150 3375);
DISPLAY 0.723404 (-2150 3375);
PAINT GREEN (-2150 3375);
DISPLAY INVISIBLE (-2150 3375);
FORCEPROP 1 LAST COMMENT_BODY TRUE
J 0
(-2520 3405);
DISPLAY 0.872340 (-2520 3405);
PAINT GREEN (-2520 3405);
DISPLAY INVISIBLE (-2520 3405);
FORCEPROP 2 LAST PATH I193
J 0
(-2275 3550);
DISPLAY 0.680851 (-2275 3550);
DISPLAY INVISIBLE (-2275 3550);
FORCEADD OFFPAGE..2
(-2475 3450);
FORCEPROP 2 LAST $XR0 47 
J 0
(-2286 3450);
DISPLAY 0.638298 (-2286 3450);
PAINT MONO (-2286 3450);
FORCEPROP 2 LAST CDS_LIB mstr_standard
J 0
(-2475 3450);
DISPLAY 0.723404 (-2475 3450);
PAINT MONO (-2475 3450);
DISPLAY INVISIBLE (-2475 3450);
FORCEPROP 1 LAST OFFPAGE TRUE
J 0
(-2150 3325);
DISPLAY 0.723404 (-2150 3325);
PAINT GREEN (-2150 3325);
DISPLAY INVISIBLE (-2150 3325);
FORCEPROP 1 LAST COMMENT_BODY TRUE
J 0
(-2520 3355);
DISPLAY 0.872340 (-2520 3355);
PAINT GREEN (-2520 3355);
DISPLAY INVISIBLE (-2520 3355);
FORCEPROP 2 LAST PATH I194
J 0
(-2275 3500);
DISPLAY 0.680851 (-2275 3500);
DISPLAY INVISIBLE (-2275 3500);
FORCEADD TAP..1
(-3275 4350);
FORCEPROP 3 LASTPIN (-3325 4350) SIG_NAME M_K_CPU1_SA_DQS_DN<8>
J 0
(-3315 4360);
DISPLAY 0.659574 (-3315 4360);
PAINT MONO (-3315 4360);
DISPLAY INVISIBLE (-3315 4360);
FORCEPROP 1 LASTPIN (-3325 4350) BN 8
J 0
(-3337 4358);
DISPLAY 0.489362 (-3337 4358);
PAINT GREEN (-3337 4358);
FORCEPROP 2 LAST CDS_LIB mstr_standard
J 0
(-3275 4350);
DISPLAY 0.723404 (-3275 4350);
PAINT MONO (-3275 4350);
DISPLAY INVISIBLE (-3275 4350);
FORCEPROP 1 LAST BODY_TYPE PLUMBING
J 0
(-3275 4400);
DISPLAY 0.872340 (-3275 4400);
PAINT GREEN (-3275 4400);
DISPLAY INVISIBLE (-3275 4400);
FORCEPROP 1 LAST HDL_TAP TRUE
J 0
(-2950 4225);
DISPLAY 0.872340 (-2950 4225);
DISPLAY INVISIBLE (-2950 4225);
FORCEPROP 1 LAST PATH I195
J 0
(-3277 4350);
DISPLAY 0.872340 (-3277 4350);
PAINT GREEN (-3277 4350);
DISPLAY INVISIBLE (-3277 4350);
FORCEADD TAP..1
(-3275 4450);
FORCEPROP 3 LASTPIN (-3325 4450) SIG_NAME M_K_CPU1_SA_DQS_DN<9>
J 0
(-3315 4460);
DISPLAY 0.659574 (-3315 4460);
PAINT MONO (-3315 4460);
DISPLAY INVISIBLE (-3315 4460);
FORCEPROP 1 LASTPIN (-3325 4450) BN 9
J 0
(-3337 4458);
DISPLAY 0.489362 (-3337 4458);
PAINT GREEN (-3337 4458);
FORCEPROP 2 LAST CDS_LIB mstr_standard
J 0
(-3275 4450);
DISPLAY 0.723404 (-3275 4450);
PAINT MONO (-3275 4450);
DISPLAY INVISIBLE (-3275 4450);
FORCEPROP 1 LAST BODY_TYPE PLUMBING
J 0
(-3275 4500);
DISPLAY 0.872340 (-3275 4500);
PAINT GREEN (-3275 4500);
DISPLAY INVISIBLE (-3275 4500);
FORCEPROP 1 LAST HDL_TAP TRUE
J 0
(-2950 4325);
DISPLAY 0.872340 (-2950 4325);
DISPLAY INVISIBLE (-2950 4325);
FORCEPROP 1 LAST PATH I196
J 0
(-3277 4450);
DISPLAY 0.872340 (-3277 4450);
PAINT GREEN (-3277 4450);
DISPLAY INVISIBLE (-3277 4450);
FORCEADD TAP..1
(-3475 4500);
FORCEPROP 3 LASTPIN (-3525 4500) SIG_NAME M_K_CPU1_SA_DQS_DP<9>
J 0
(-3515 4510);
DISPLAY 0.659574 (-3515 4510);
PAINT MONO (-3515 4510);
DISPLAY INVISIBLE (-3515 4510);
FORCEPROP 1 LASTPIN (-3525 4500) BN 9
J 0
(-3537 4508);
DISPLAY 0.489362 (-3537 4508);
PAINT GREEN (-3537 4508);
FORCEPROP 2 LAST CDS_LIB mstr_standard
J 0
(-3475 4500);
DISPLAY 0.723404 (-3475 4500);
PAINT MONO (-3475 4500);
DISPLAY INVISIBLE (-3475 4500);
FORCEPROP 1 LAST BODY_TYPE PLUMBING
J 0
(-3475 4550);
DISPLAY 0.872340 (-3475 4550);
PAINT GREEN (-3475 4550);
DISPLAY INVISIBLE (-3475 4550);
FORCEPROP 1 LAST HDL_TAP TRUE
J 0
(-3150 4375);
DISPLAY 0.872340 (-3150 4375);
DISPLAY INVISIBLE (-3150 4375);
FORCEPROP 1 LAST PATH I197
J 0
(-3477 4500);
DISPLAY 0.872340 (-3477 4500);
PAINT GREEN (-3477 4500);
DISPLAY INVISIBLE (-3477 4500);
FORCEADD TAP..1
(-3475 4400);
FORCEPROP 3 LASTPIN (-3525 4400) SIG_NAME M_K_CPU1_SA_DQS_DP<8>
J 0
(-3515 4410);
DISPLAY 0.659574 (-3515 4410);
PAINT MONO (-3515 4410);
DISPLAY INVISIBLE (-3515 4410);
FORCEPROP 1 LASTPIN (-3525 4400) BN 8
J 0
(-3537 4408);
DISPLAY 0.489362 (-3537 4408);
PAINT GREEN (-3537 4408);
FORCEPROP 2 LAST CDS_LIB mstr_standard
J 0
(-3475 4400);
DISPLAY 0.723404 (-3475 4400);
PAINT MONO (-3475 4400);
DISPLAY INVISIBLE (-3475 4400);
FORCEPROP 1 LAST BODY_TYPE PLUMBING
J 0
(-3475 4450);
DISPLAY 0.872340 (-3475 4450);
PAINT GREEN (-3475 4450);
DISPLAY INVISIBLE (-3475 4450);
FORCEPROP 1 LAST HDL_TAP TRUE
J 0
(-3150 4275);
DISPLAY 0.872340 (-3150 4275);
DISPLAY INVISIBLE (-3150 4275);
FORCEPROP 1 LAST PATH I198
J 0
(-3477 4400);
DISPLAY 0.872340 (-3477 4400);
PAINT GREEN (-3477 4400);
DISPLAY INVISIBLE (-3477 4400);
FORCEADD TAP..1
(-3275 4250);
FORCEPROP 3 LASTPIN (-3325 4250) SIG_NAME M_K_CPU1_SA_DQS_DN<7>
J 0
(-3315 4260);
DISPLAY 0.659574 (-3315 4260);
PAINT MONO (-3315 4260);
DISPLAY INVISIBLE (-3315 4260);
FORCEPROP 1 LASTPIN (-3325 4250) BN 7
J 0
(-3337 4258);
DISPLAY 0.489362 (-3337 4258);
PAINT GREEN (-3337 4258);
FORCEPROP 2 LAST CDS_LIB mstr_standard
J 0
(-3275 4250);
DISPLAY 0.723404 (-3275 4250);
PAINT MONO (-3275 4250);
DISPLAY INVISIBLE (-3275 4250);
FORCEPROP 1 LAST BODY_TYPE PLUMBING
J 0
(-3275 4300);
DISPLAY 0.872340 (-3275 4300);
PAINT GREEN (-3275 4300);
DISPLAY INVISIBLE (-3275 4300);
FORCEPROP 1 LAST HDL_TAP TRUE
J 0
(-2950 4125);
DISPLAY 0.872340 (-2950 4125);
DISPLAY INVISIBLE (-2950 4125);
FORCEPROP 1 LAST PATH I199
J 0
(-3277 4250);
DISPLAY 0.872340 (-3277 4250);
PAINT GREEN (-3277 4250);
DISPLAY INVISIBLE (-3277 4250);
FORCEADD OFFPAGE..5
(-8300 1925);
FORCEPROP 2 LAST $XR0 47 
J 0
(-8554 1925);
DISPLAY 0.638298 (-8554 1925);
PAINT MONO (-8554 1925);
FORCEPROP 2 LAST CDS_LIB mstr_standard
J 0
(-8300 1925);
DISPLAY 0.808511 (-8300 1925);
DISPLAY INVISIBLE (-8300 1925);
FORCEPROP 1 LAST OFFPAGE TRUE
J 0
(-7975 1800);
DISPLAY 0.872340 (-7975 1800);
PAINT GREEN (-7975 1800);
DISPLAY INVISIBLE (-7975 1800);
FORCEPROP 1 LAST COMMENT_BODY TRUE
J 0
(-8200 1850);
DISPLAY 0.872340 (-8200 1850);
PAINT GREEN (-8200 1850);
DISPLAY INVISIBLE (-8200 1850);
FORCEPROP 2 LAST PATH I2
J 0
(-8550 1975);
DISPLAY 1.021277 (-8550 1975);
DISPLAY INVISIBLE (-8550 1975);
FORCEADD OFFPAGE..1
(-8300 5375);
FORCEPROP 2 LAST $XR0 47 
J 0
(-8521 5375);
DISPLAY 0.638298 (-8521 5375);
PAINT MONO (-8521 5375);
FORCEPROP 2 LAST CDS_LIB mstr_standard
J 0
(-8300 5375);
DISPLAY 0.723404 (-8300 5375);
PAINT MONO (-8300 5375);
DISPLAY INVISIBLE (-8300 5375);
FORCEPROP 1 LAST OFFPAGE TRUE
J 0
(-7975 5250);
DISPLAY 0.872340 (-7975 5250);
PAINT GREEN (-7975 5250);
DISPLAY INVISIBLE (-7975 5250);
FORCEPROP 1 LAST COMMENT_BODY TRUE
J 0
(-8175 5275);
DISPLAY 0.872340 (-8175 5275);
PAINT GREEN (-8175 5275);
DISPLAY INVISIBLE (-8175 5275);
FORCEPROP 2 LAST PATH I20
J 0
(-8500 5425);
DISPLAY 1.021277 (-8500 5425);
DISPLAY INVISIBLE (-8500 5425);
FORCEADD TAP..1
(-3275 4150);
FORCEPROP 3 LASTPIN (-3325 4150) SIG_NAME M_K_CPU1_SA_DQS_DN<6>
J 0
(-3315 4160);
DISPLAY 0.659574 (-3315 4160);
PAINT MONO (-3315 4160);
DISPLAY INVISIBLE (-3315 4160);
FORCEPROP 1 LASTPIN (-3325 4150) BN 6
J 0
(-3337 4158);
DISPLAY 0.489362 (-3337 4158);
PAINT GREEN (-3337 4158);
FORCEPROP 2 LAST CDS_LIB mstr_standard
J 0
(-3275 4150);
DISPLAY 0.723404 (-3275 4150);
PAINT MONO (-3275 4150);
DISPLAY INVISIBLE (-3275 4150);
FORCEPROP 1 LAST BODY_TYPE PLUMBING
J 0
(-3275 4200);
DISPLAY 0.872340 (-3275 4200);
PAINT GREEN (-3275 4200);
DISPLAY INVISIBLE (-3275 4200);
FORCEPROP 1 LAST HDL_TAP TRUE
J 0
(-2950 4025);
DISPLAY 0.872340 (-2950 4025);
DISPLAY INVISIBLE (-2950 4025);
FORCEPROP 1 LAST PATH I200
J 0
(-3277 4150);
DISPLAY 0.872340 (-3277 4150);
PAINT GREEN (-3277 4150);
DISPLAY INVISIBLE (-3277 4150);
FORCEADD TAP..1
(-3475 4300);
FORCEPROP 3 LASTPIN (-3525 4300) SIG_NAME M_K_CPU1_SA_DQS_DP<7>
J 0
(-3515 4310);
DISPLAY 0.659574 (-3515 4310);
PAINT MONO (-3515 4310);
DISPLAY INVISIBLE (-3515 4310);
FORCEPROP 1 LASTPIN (-3525 4300) BN 7
J 0
(-3537 4308);
DISPLAY 0.489362 (-3537 4308);
PAINT GREEN (-3537 4308);
FORCEPROP 2 LAST CDS_LIB mstr_standard
J 0
(-3475 4300);
DISPLAY 0.723404 (-3475 4300);
PAINT MONO (-3475 4300);
DISPLAY INVISIBLE (-3475 4300);
FORCEPROP 1 LAST BODY_TYPE PLUMBING
J 0
(-3475 4350);
DISPLAY 0.872340 (-3475 4350);
PAINT GREEN (-3475 4350);
DISPLAY INVISIBLE (-3475 4350);
FORCEPROP 1 LAST HDL_TAP TRUE
J 0
(-3150 4175);
DISPLAY 0.872340 (-3150 4175);
DISPLAY INVISIBLE (-3150 4175);
FORCEPROP 1 LAST PATH I201
J 0
(-3477 4300);
DISPLAY 0.872340 (-3477 4300);
PAINT GREEN (-3477 4300);
DISPLAY INVISIBLE (-3477 4300);
FORCEADD TAP..1
(-3475 4200);
FORCEPROP 3 LASTPIN (-3525 4200) SIG_NAME M_K_CPU1_SA_DQS_DP<6>
J 0
(-3515 4210);
DISPLAY 0.659574 (-3515 4210);
PAINT MONO (-3515 4210);
DISPLAY INVISIBLE (-3515 4210);
FORCEPROP 1 LASTPIN (-3525 4200) BN 6
J 0
(-3537 4208);
DISPLAY 0.489362 (-3537 4208);
PAINT GREEN (-3537 4208);
FORCEPROP 2 LAST CDS_LIB mstr_standard
J 0
(-3475 4200);
DISPLAY 0.723404 (-3475 4200);
PAINT MONO (-3475 4200);
DISPLAY INVISIBLE (-3475 4200);
FORCEPROP 1 LAST BODY_TYPE PLUMBING
J 0
(-3475 4250);
DISPLAY 0.872340 (-3475 4250);
PAINT GREEN (-3475 4250);
DISPLAY INVISIBLE (-3475 4250);
FORCEPROP 1 LAST HDL_TAP TRUE
J 0
(-3150 4075);
DISPLAY 0.872340 (-3150 4075);
DISPLAY INVISIBLE (-3150 4075);
FORCEPROP 1 LAST PATH I202
J 0
(-3477 4200);
DISPLAY 0.872340 (-3477 4200);
PAINT GREEN (-3477 4200);
DISPLAY INVISIBLE (-3477 4200);
FORCEADD TAP..1
(-3475 4100);
FORCEPROP 3 LASTPIN (-3525 4100) SIG_NAME M_K_CPU1_SA_DQS_DP<5>
J 0
(-3515 4110);
DISPLAY 0.659574 (-3515 4110);
PAINT MONO (-3515 4110);
DISPLAY INVISIBLE (-3515 4110);
FORCEPROP 1 LASTPIN (-3525 4100) BN 5
J 0
(-3537 4108);
DISPLAY 0.489362 (-3537 4108);
PAINT GREEN (-3537 4108);
FORCEPROP 2 LAST CDS_LIB mstr_standard
J 0
(-3475 4100);
DISPLAY 0.723404 (-3475 4100);
PAINT MONO (-3475 4100);
DISPLAY INVISIBLE (-3475 4100);
FORCEPROP 1 LAST BODY_TYPE PLUMBING
J 0
(-3475 4150);
DISPLAY 0.872340 (-3475 4150);
PAINT GREEN (-3475 4150);
DISPLAY INVISIBLE (-3475 4150);
FORCEPROP 1 LAST HDL_TAP TRUE
J 0
(-3150 3975);
DISPLAY 0.872340 (-3150 3975);
DISPLAY INVISIBLE (-3150 3975);
FORCEPROP 1 LAST PATH I203
J 0
(-3477 4100);
DISPLAY 0.872340 (-3477 4100);
PAINT GREEN (-3477 4100);
DISPLAY INVISIBLE (-3477 4100);
FORCEADD TAP..1
(-3275 4050);
FORCEPROP 3 LASTPIN (-3325 4050) SIG_NAME M_K_CPU1_SA_DQS_DN<5>
J 0
(-3315 4060);
DISPLAY 0.659574 (-3315 4060);
PAINT MONO (-3315 4060);
DISPLAY INVISIBLE (-3315 4060);
FORCEPROP 1 LASTPIN (-3325 4050) BN 5
J 0
(-3337 4058);
DISPLAY 0.489362 (-3337 4058);
PAINT GREEN (-3337 4058);
FORCEPROP 2 LAST CDS_LIB mstr_standard
J 0
(-3275 4050);
DISPLAY 0.723404 (-3275 4050);
PAINT MONO (-3275 4050);
DISPLAY INVISIBLE (-3275 4050);
FORCEPROP 1 LAST BODY_TYPE PLUMBING
J 0
(-3275 4100);
DISPLAY 0.872340 (-3275 4100);
PAINT GREEN (-3275 4100);
DISPLAY INVISIBLE (-3275 4100);
FORCEPROP 1 LAST HDL_TAP TRUE
J 0
(-2950 3925);
DISPLAY 0.872340 (-2950 3925);
DISPLAY INVISIBLE (-2950 3925);
FORCEPROP 1 LAST PATH I204
J 0
(-3277 4050);
DISPLAY 0.872340 (-3277 4050);
PAINT GREEN (-3277 4050);
DISPLAY INVISIBLE (-3277 4050);
FORCEADD TAP..1
(-3275 3850);
FORCEPROP 3 LASTPIN (-3325 3850) SIG_NAME M_K_CPU1_SA_DQS_DN<3>
J 0
(-3315 3860);
DISPLAY 0.659574 (-3315 3860);
PAINT MONO (-3315 3860);
DISPLAY INVISIBLE (-3315 3860);
FORCEPROP 1 LASTPIN (-3325 3850) BN 3
J 0
(-3337 3858);
DISPLAY 0.489362 (-3337 3858);
PAINT GREEN (-3337 3858);
FORCEPROP 2 LAST CDS_LIB mstr_standard
J 0
(-3275 3850);
DISPLAY 0.723404 (-3275 3850);
PAINT MONO (-3275 3850);
DISPLAY INVISIBLE (-3275 3850);
FORCEPROP 1 LAST BODY_TYPE PLUMBING
J 0
(-3275 3900);
DISPLAY 0.872340 (-3275 3900);
PAINT GREEN (-3275 3900);
DISPLAY INVISIBLE (-3275 3900);
FORCEPROP 1 LAST HDL_TAP TRUE
J 0
(-2950 3725);
DISPLAY 0.872340 (-2950 3725);
DISPLAY INVISIBLE (-2950 3725);
FORCEPROP 1 LAST PATH I205
J 0
(-3277 3850);
DISPLAY 0.872340 (-3277 3850);
PAINT GREEN (-3277 3850);
DISPLAY INVISIBLE (-3277 3850);
FORCEADD TAP..1
(-3275 3950);
FORCEPROP 3 LASTPIN (-3325 3950) SIG_NAME M_K_CPU1_SA_DQS_DN<4>
J 0
(-3315 3960);
DISPLAY 0.659574 (-3315 3960);
PAINT MONO (-3315 3960);
DISPLAY INVISIBLE (-3315 3960);
FORCEPROP 1 LASTPIN (-3325 3950) BN 4
J 0
(-3337 3958);
DISPLAY 0.489362 (-3337 3958);
PAINT GREEN (-3337 3958);
FORCEPROP 2 LAST CDS_LIB mstr_standard
J 0
(-3275 3950);
DISPLAY 0.723404 (-3275 3950);
PAINT MONO (-3275 3950);
DISPLAY INVISIBLE (-3275 3950);
FORCEPROP 1 LAST BODY_TYPE PLUMBING
J 0
(-3275 4000);
DISPLAY 0.872340 (-3275 4000);
PAINT GREEN (-3275 4000);
DISPLAY INVISIBLE (-3275 4000);
FORCEPROP 1 LAST HDL_TAP TRUE
J 0
(-2950 3825);
DISPLAY 0.872340 (-2950 3825);
DISPLAY INVISIBLE (-2950 3825);
FORCEPROP 1 LAST PATH I206
J 0
(-3277 3950);
DISPLAY 0.872340 (-3277 3950);
PAINT GREEN (-3277 3950);
DISPLAY INVISIBLE (-3277 3950);
FORCEADD TAP..1
(-3475 4000);
FORCEPROP 3 LASTPIN (-3525 4000) SIG_NAME M_K_CPU1_SA_DQS_DP<4>
J 0
(-3515 4010);
DISPLAY 0.659574 (-3515 4010);
PAINT MONO (-3515 4010);
DISPLAY INVISIBLE (-3515 4010);
FORCEPROP 1 LASTPIN (-3525 4000) BN 4
J 0
(-3537 4008);
DISPLAY 0.489362 (-3537 4008);
PAINT GREEN (-3537 4008);
FORCEPROP 2 LAST CDS_LIB mstr_standard
J 0
(-3475 4000);
DISPLAY 0.723404 (-3475 4000);
PAINT MONO (-3475 4000);
DISPLAY INVISIBLE (-3475 4000);
FORCEPROP 1 LAST BODY_TYPE PLUMBING
J 0
(-3475 4050);
DISPLAY 0.872340 (-3475 4050);
PAINT GREEN (-3475 4050);
DISPLAY INVISIBLE (-3475 4050);
FORCEPROP 1 LAST HDL_TAP TRUE
J 0
(-3150 3875);
DISPLAY 0.872340 (-3150 3875);
DISPLAY INVISIBLE (-3150 3875);
FORCEPROP 1 LAST PATH I207
J 0
(-3477 4000);
DISPLAY 0.872340 (-3477 4000);
PAINT GREEN (-3477 4000);
DISPLAY INVISIBLE (-3477 4000);
FORCEADD TAP..1
(-3475 3900);
FORCEPROP 3 LASTPIN (-3525 3900) SIG_NAME M_K_CPU1_SA_DQS_DP<3>
J 0
(-3515 3910);
DISPLAY 0.659574 (-3515 3910);
PAINT MONO (-3515 3910);
DISPLAY INVISIBLE (-3515 3910);
FORCEPROP 1 LASTPIN (-3525 3900) BN 3
J 0
(-3537 3908);
DISPLAY 0.489362 (-3537 3908);
PAINT GREEN (-3537 3908);
FORCEPROP 2 LAST CDS_LIB mstr_standard
J 0
(-3475 3900);
DISPLAY 0.723404 (-3475 3900);
PAINT MONO (-3475 3900);
DISPLAY INVISIBLE (-3475 3900);
FORCEPROP 1 LAST BODY_TYPE PLUMBING
J 0
(-3475 3950);
DISPLAY 0.872340 (-3475 3950);
PAINT GREEN (-3475 3950);
DISPLAY INVISIBLE (-3475 3950);
FORCEPROP 1 LAST HDL_TAP TRUE
J 0
(-3150 3775);
DISPLAY 0.872340 (-3150 3775);
DISPLAY INVISIBLE (-3150 3775);
FORCEPROP 1 LAST PATH I208
J 0
(-3477 3900);
DISPLAY 0.872340 (-3477 3900);
PAINT GREEN (-3477 3900);
DISPLAY INVISIBLE (-3477 3900);
FORCEADD TAP..1
(-3275 3750);
FORCEPROP 3 LASTPIN (-3325 3750) SIG_NAME M_K_CPU1_SA_DQS_DN<2>
J 0
(-3315 3760);
DISPLAY 0.659574 (-3315 3760);
PAINT MONO (-3315 3760);
DISPLAY INVISIBLE (-3315 3760);
FORCEPROP 1 LASTPIN (-3325 3750) BN 2
J 0
(-3337 3758);
DISPLAY 0.489362 (-3337 3758);
PAINT GREEN (-3337 3758);
FORCEPROP 2 LAST CDS_LIB mstr_standard
J 0
(-3275 3750);
DISPLAY 0.723404 (-3275 3750);
PAINT MONO (-3275 3750);
DISPLAY INVISIBLE (-3275 3750);
FORCEPROP 1 LAST BODY_TYPE PLUMBING
J 0
(-3275 3800);
DISPLAY 0.872340 (-3275 3800);
PAINT GREEN (-3275 3800);
DISPLAY INVISIBLE (-3275 3800);
FORCEPROP 1 LAST HDL_TAP TRUE
J 0
(-2950 3625);
DISPLAY 0.872340 (-2950 3625);
DISPLAY INVISIBLE (-2950 3625);
FORCEPROP 1 LAST PATH I209
J 0
(-3277 3750);
DISPLAY 0.872340 (-3277 3750);
PAINT GREEN (-3277 3750);
DISPLAY INVISIBLE (-3277 3750);
FORCEADD OFFPAGE..1
(-8300 4975);
FORCEPROP 2 LAST $XR0 47 
J 0
(-8521 4975);
DISPLAY 0.638298 (-8521 4975);
PAINT MONO (-8521 4975);
FORCEPROP 2 LAST CDS_LIB mstr_standard
J 0
(-8300 4975);
DISPLAY 0.723404 (-8300 4975);
PAINT MONO (-8300 4975);
DISPLAY INVISIBLE (-8300 4975);
FORCEPROP 1 LAST OFFPAGE TRUE
J 0
(-7975 4850);
DISPLAY 0.872340 (-7975 4850);
PAINT GREEN (-7975 4850);
DISPLAY INVISIBLE (-7975 4850);
FORCEPROP 1 LAST COMMENT_BODY TRUE
J 0
(-8175 4875);
DISPLAY 0.872340 (-8175 4875);
PAINT GREEN (-8175 4875);
DISPLAY INVISIBLE (-8175 4875);
FORCEPROP 2 LAST PATH I21
J 0
(-8500 5025);
DISPLAY 1.021277 (-8500 5025);
DISPLAY INVISIBLE (-8500 5025);
FORCEADD TAP..1
(-3275 3650);
FORCEPROP 3 LASTPIN (-3325 3650) SIG_NAME M_K_CPU1_SA_DQS_DN<1>
J 0
(-3315 3660);
DISPLAY 0.659574 (-3315 3660);
PAINT MONO (-3315 3660);
DISPLAY INVISIBLE (-3315 3660);
FORCEPROP 1 LASTPIN (-3325 3650) BN 1
J 0
(-3337 3658);
DISPLAY 0.489362 (-3337 3658);
PAINT GREEN (-3337 3658);
FORCEPROP 2 LAST CDS_LIB mstr_standard
J 0
(-3275 3650);
DISPLAY 0.723404 (-3275 3650);
PAINT MONO (-3275 3650);
DISPLAY INVISIBLE (-3275 3650);
FORCEPROP 1 LAST BODY_TYPE PLUMBING
J 0
(-3275 3700);
DISPLAY 0.872340 (-3275 3700);
PAINT GREEN (-3275 3700);
DISPLAY INVISIBLE (-3275 3700);
FORCEPROP 1 LAST HDL_TAP TRUE
J 0
(-2950 3525);
DISPLAY 0.872340 (-2950 3525);
DISPLAY INVISIBLE (-2950 3525);
FORCEPROP 1 LAST PATH I210
J 0
(-3277 3650);
DISPLAY 0.872340 (-3277 3650);
PAINT GREEN (-3277 3650);
DISPLAY INVISIBLE (-3277 3650);
FORCEADD TAP..1
(-3475 3800);
FORCEPROP 3 LASTPIN (-3525 3800) SIG_NAME M_K_CPU1_SA_DQS_DP<2>
J 0
(-3515 3810);
DISPLAY 0.659574 (-3515 3810);
PAINT MONO (-3515 3810);
DISPLAY INVISIBLE (-3515 3810);
FORCEPROP 1 LASTPIN (-3525 3800) BN 2
J 0
(-3537 3808);
DISPLAY 0.489362 (-3537 3808);
PAINT GREEN (-3537 3808);
FORCEPROP 2 LAST CDS_LIB mstr_standard
J 0
(-3475 3800);
DISPLAY 0.723404 (-3475 3800);
PAINT MONO (-3475 3800);
DISPLAY INVISIBLE (-3475 3800);
FORCEPROP 1 LAST BODY_TYPE PLUMBING
J 0
(-3475 3850);
DISPLAY 0.872340 (-3475 3850);
PAINT GREEN (-3475 3850);
DISPLAY INVISIBLE (-3475 3850);
FORCEPROP 1 LAST HDL_TAP TRUE
J 0
(-3150 3675);
DISPLAY 0.872340 (-3150 3675);
DISPLAY INVISIBLE (-3150 3675);
FORCEPROP 1 LAST PATH I211
J 0
(-3477 3800);
DISPLAY 0.872340 (-3477 3800);
PAINT GREEN (-3477 3800);
DISPLAY INVISIBLE (-3477 3800);
FORCEADD TAP..1
(-3475 3700);
FORCEPROP 3 LASTPIN (-3525 3700) SIG_NAME M_K_CPU1_SA_DQS_DP<1>
J 0
(-3515 3710);
DISPLAY 0.659574 (-3515 3710);
PAINT MONO (-3515 3710);
DISPLAY INVISIBLE (-3515 3710);
FORCEPROP 1 LASTPIN (-3525 3700) BN 1
J 0
(-3537 3708);
DISPLAY 0.489362 (-3537 3708);
PAINT GREEN (-3537 3708);
FORCEPROP 2 LAST CDS_LIB mstr_standard
J 0
(-3475 3700);
DISPLAY 0.723404 (-3475 3700);
PAINT MONO (-3475 3700);
DISPLAY INVISIBLE (-3475 3700);
FORCEPROP 1 LAST BODY_TYPE PLUMBING
J 0
(-3475 3750);
DISPLAY 0.872340 (-3475 3750);
PAINT GREEN (-3475 3750);
DISPLAY INVISIBLE (-3475 3750);
FORCEPROP 1 LAST HDL_TAP TRUE
J 0
(-3150 3575);
DISPLAY 0.872340 (-3150 3575);
DISPLAY INVISIBLE (-3150 3575);
FORCEPROP 1 LAST PATH I212
J 0
(-3477 3700);
DISPLAY 0.872340 (-3477 3700);
PAINT GREEN (-3477 3700);
DISPLAY INVISIBLE (-3477 3700);
FORCEADD TAP..1
(-3475 3600);
FORCEPROP 3 LASTPIN (-3525 3600) SIG_NAME M_K_CPU1_SA_DQS_DP<0>
J 0
(-3515 3610);
DISPLAY 0.659574 (-3515 3610);
PAINT MONO (-3515 3610);
DISPLAY INVISIBLE (-3515 3610);
FORCEPROP 1 LASTPIN (-3525 3600) BN 0
J 0
(-3537 3608);
DISPLAY 0.489362 (-3537 3608);
PAINT GREEN (-3537 3608);
FORCEPROP 2 LAST CDS_LIB mstr_standard
J 0
(-3475 3600);
DISPLAY 0.723404 (-3475 3600);
PAINT MONO (-3475 3600);
DISPLAY INVISIBLE (-3475 3600);
FORCEPROP 1 LAST BODY_TYPE PLUMBING
J 0
(-3475 3650);
DISPLAY 0.872340 (-3475 3650);
PAINT GREEN (-3475 3650);
DISPLAY INVISIBLE (-3475 3650);
FORCEPROP 1 LAST HDL_TAP TRUE
J 0
(-3150 3475);
DISPLAY 0.872340 (-3150 3475);
DISPLAY INVISIBLE (-3150 3475);
FORCEPROP 1 LAST PATH I213
J 0
(-3477 3600);
DISPLAY 0.872340 (-3477 3600);
PAINT GREEN (-3477 3600);
DISPLAY INVISIBLE (-3477 3600);
FORCEADD TAP..1
(-3275 3550);
FORCEPROP 3 LASTPIN (-3325 3550) SIG_NAME M_K_CPU1_SA_DQS_DN<0>
J 0
(-3315 3560);
DISPLAY 0.659574 (-3315 3560);
PAINT MONO (-3315 3560);
DISPLAY INVISIBLE (-3315 3560);
FORCEPROP 1 LASTPIN (-3325 3550) BN 0
J 0
(-3337 3558);
DISPLAY 0.489362 (-3337 3558);
PAINT GREEN (-3337 3558);
FORCEPROP 2 LAST CDS_LIB mstr_standard
J 0
(-3275 3550);
DISPLAY 0.723404 (-3275 3550);
PAINT MONO (-3275 3550);
DISPLAY INVISIBLE (-3275 3550);
FORCEPROP 1 LAST BODY_TYPE PLUMBING
J 0
(-3275 3600);
DISPLAY 0.872340 (-3275 3600);
PAINT GREEN (-3275 3600);
DISPLAY INVISIBLE (-3275 3600);
FORCEPROP 1 LAST HDL_TAP TRUE
J 0
(-2950 3425);
DISPLAY 0.872340 (-2950 3425);
DISPLAY INVISIBLE (-2950 3425);
FORCEPROP 1 LAST PATH I214
J 0
(-3277 3550);
DISPLAY 0.872340 (-3277 3550);
PAINT GREEN (-3277 3550);
DISPLAY INVISIBLE (-3277 3550);
FORCEADD TAP..1
(-3275 3400);
FORCEPROP 3 LASTPIN (-3325 3400) SIG_NAME M_K_CPU1_SB_DQS_DN<9>
J 0
(-3315 3410);
DISPLAY 0.659574 (-3315 3410);
PAINT MONO (-3315 3410);
DISPLAY INVISIBLE (-3315 3410);
FORCEPROP 1 LASTPIN (-3325 3400) BN 9
J 0
(-3337 3408);
DISPLAY 0.489362 (-3337 3408);
PAINT GREEN (-3337 3408);
FORCEPROP 2 LAST CDS_LIB mstr_standard
J 0
(-3275 3400);
DISPLAY 0.723404 (-3275 3400);
PAINT MONO (-3275 3400);
DISPLAY INVISIBLE (-3275 3400);
FORCEPROP 1 LAST BODY_TYPE PLUMBING
J 0
(-3275 3450);
DISPLAY 0.872340 (-3275 3450);
PAINT GREEN (-3275 3450);
DISPLAY INVISIBLE (-3275 3450);
FORCEPROP 1 LAST HDL_TAP TRUE
J 0
(-2950 3275);
DISPLAY 0.872340 (-2950 3275);
DISPLAY INVISIBLE (-2950 3275);
FORCEPROP 1 LAST PATH I215
J 0
(-3277 3400);
DISPLAY 0.872340 (-3277 3400);
PAINT GREEN (-3277 3400);
DISPLAY INVISIBLE (-3277 3400);
FORCEADD TAP..1
(-3475 3450);
FORCEPROP 3 LASTPIN (-3525 3450) SIG_NAME M_K_CPU1_SB_DQS_DP<9>
J 0
(-3515 3460);
DISPLAY 0.659574 (-3515 3460);
PAINT MONO (-3515 3460);
DISPLAY INVISIBLE (-3515 3460);
FORCEPROP 1 LASTPIN (-3525 3450) BN 9
J 0
(-3537 3458);
DISPLAY 0.489362 (-3537 3458);
PAINT GREEN (-3537 3458);
FORCEPROP 2 LAST CDS_LIB mstr_standard
J 0
(-3475 3450);
DISPLAY 0.723404 (-3475 3450);
PAINT MONO (-3475 3450);
DISPLAY INVISIBLE (-3475 3450);
FORCEPROP 1 LAST BODY_TYPE PLUMBING
J 0
(-3475 3500);
DISPLAY 0.872340 (-3475 3500);
PAINT GREEN (-3475 3500);
DISPLAY INVISIBLE (-3475 3500);
FORCEPROP 1 LAST HDL_TAP TRUE
J 0
(-3150 3325);
DISPLAY 0.872340 (-3150 3325);
DISPLAY INVISIBLE (-3150 3325);
FORCEPROP 1 LAST PATH I216
J 0
(-3477 3450);
DISPLAY 0.872340 (-3477 3450);
PAINT GREEN (-3477 3450);
DISPLAY INVISIBLE (-3477 3450);
FORCEADD TAP..1
(-3475 3350);
FORCEPROP 3 LASTPIN (-3525 3350) SIG_NAME M_K_CPU1_SB_DQS_DP<8>
J 0
(-3515 3360);
DISPLAY 0.659574 (-3515 3360);
PAINT MONO (-3515 3360);
DISPLAY INVISIBLE (-3515 3360);
FORCEPROP 1 LASTPIN (-3525 3350) BN 8
J 0
(-3537 3358);
DISPLAY 0.489362 (-3537 3358);
PAINT GREEN (-3537 3358);
FORCEPROP 2 LAST CDS_LIB mstr_standard
J 0
(-3475 3350);
DISPLAY 0.723404 (-3475 3350);
PAINT MONO (-3475 3350);
DISPLAY INVISIBLE (-3475 3350);
FORCEPROP 1 LAST BODY_TYPE PLUMBING
J 0
(-3475 3400);
DISPLAY 0.872340 (-3475 3400);
PAINT GREEN (-3475 3400);
DISPLAY INVISIBLE (-3475 3400);
FORCEPROP 1 LAST HDL_TAP TRUE
J 0
(-3150 3225);
DISPLAY 0.872340 (-3150 3225);
DISPLAY INVISIBLE (-3150 3225);
FORCEPROP 1 LAST PATH I217
J 0
(-3477 3350);
DISPLAY 0.872340 (-3477 3350);
PAINT GREEN (-3477 3350);
DISPLAY INVISIBLE (-3477 3350);
FORCEADD TAP..1
(-3275 3200);
FORCEPROP 3 LASTPIN (-3325 3200) SIG_NAME M_K_CPU1_SB_DQS_DN<7>
J 0
(-3315 3210);
DISPLAY 0.659574 (-3315 3210);
PAINT MONO (-3315 3210);
DISPLAY INVISIBLE (-3315 3210);
FORCEPROP 1 LASTPIN (-3325 3200) BN 7
J 0
(-3337 3208);
DISPLAY 0.489362 (-3337 3208);
PAINT GREEN (-3337 3208);
FORCEPROP 2 LAST CDS_LIB mstr_standard
J 0
(-3275 3200);
DISPLAY 0.723404 (-3275 3200);
PAINT MONO (-3275 3200);
DISPLAY INVISIBLE (-3275 3200);
FORCEPROP 1 LAST BODY_TYPE PLUMBING
J 0
(-3275 3250);
DISPLAY 0.872340 (-3275 3250);
PAINT GREEN (-3275 3250);
DISPLAY INVISIBLE (-3275 3250);
FORCEPROP 1 LAST HDL_TAP TRUE
J 0
(-2950 3075);
DISPLAY 0.872340 (-2950 3075);
DISPLAY INVISIBLE (-2950 3075);
FORCEPROP 1 LAST PATH I218
J 0
(-3277 3200);
DISPLAY 0.872340 (-3277 3200);
PAINT GREEN (-3277 3200);
DISPLAY INVISIBLE (-3277 3200);
FORCEADD TAP..1
(-3275 3300);
FORCEPROP 3 LASTPIN (-3325 3300) SIG_NAME M_K_CPU1_SB_DQS_DN<8>
J 0
(-3315 3310);
DISPLAY 0.659574 (-3315 3310);
PAINT MONO (-3315 3310);
DISPLAY INVISIBLE (-3315 3310);
FORCEPROP 1 LASTPIN (-3325 3300) BN 8
J 0
(-3337 3308);
DISPLAY 0.489362 (-3337 3308);
PAINT GREEN (-3337 3308);
FORCEPROP 2 LAST CDS_LIB mstr_standard
J 0
(-3275 3300);
DISPLAY 0.723404 (-3275 3300);
PAINT MONO (-3275 3300);
DISPLAY INVISIBLE (-3275 3300);
FORCEPROP 1 LAST BODY_TYPE PLUMBING
J 0
(-3275 3350);
DISPLAY 0.872340 (-3275 3350);
PAINT GREEN (-3275 3350);
DISPLAY INVISIBLE (-3275 3350);
FORCEPROP 1 LAST HDL_TAP TRUE
J 0
(-2950 3175);
DISPLAY 0.872340 (-2950 3175);
DISPLAY INVISIBLE (-2950 3175);
FORCEPROP 1 LAST PATH I219
J 0
(-3277 3300);
DISPLAY 0.872340 (-3277 3300);
PAINT GREEN (-3277 3300);
DISPLAY INVISIBLE (-3277 3300);
FORCEADD SCONN288_DDR506112002KQ..1
(-6850 3575);
FORCEPROP 1 LAST LOCATION J99
J 0
(-7300 5650);
DISPLAY 0.468085 (-7300 5650);
PAINT SKYBLUE (-7300 5650);
FORCEPROP 0 LAST $SEC 1
J 0
(-7300 5800);
DISPLAY 0.680851 (-7300 5800);
PAINT MONO (-7300 5800);
DISPLAY INVISIBLE (-7300 5800);
FORCEPROP 2 LAST CDS_SEC 1
J 0
(-7300 5800);
DISPLAY 1.021277 (-7300 5800);
DISPLAY INVISIBLE (-7300 5800);
FORCEPROP 0 LASTPIN (-7450 2975) $PN 62
J 2
(-7460 2985);
DISPLAY 0.680851 (-7460 2985);
PAINT MONO (-7460 2985);
FORCEPROP 0 LASTPIN (-7450 5025) $PN 66
J 2
(-7460 5035);
DISPLAY 0.680851 (-7460 5035);
PAINT MONO (-7460 5035);
FORCEPROP 0 LASTPIN (-7450 4625) $PN 76
J 2
(-7460 4635);
DISPLAY 0.680851 (-7460 4635);
PAINT MONO (-7460 4635);
FORCEPROP 0 LASTPIN (-7450 5075) $PN 211
J 2
(-7460 5085);
DISPLAY 0.680851 (-7460 5085);
PAINT MONO (-7460 5085);
FORCEPROP 0 LASTPIN (-7450 4675) $PN 221
J 2
(-7460 4685);
DISPLAY 0.680851 (-7460 4685);
PAINT MONO (-7460 4685);
FORCEPROP 0 LASTPIN (-7450 5125) $PN 68
J 2
(-7460 5135);
DISPLAY 0.680851 (-7460 5135);
PAINT MONO (-7460 5135);
FORCEPROP 0 LASTPIN (-7450 4725) $PN 78
J 2
(-7460 4735);
DISPLAY 0.680851 (-7460 4735);
PAINT MONO (-7460 4735);
FORCEPROP 0 LASTPIN (-7450 5175) $PN 213
J 2
(-7460 5185);
DISPLAY 0.680851 (-7460 5185);
PAINT MONO (-7460 5185);
FORCEPROP 0 LASTPIN (-7450 4775) $PN 223
J 2
(-7460 4785);
DISPLAY 0.680851 (-7460 4785);
PAINT MONO (-7460 4785);
FORCEPROP 0 LASTPIN (-7450 5225) $PN 70
J 2
(-7460 5235);
DISPLAY 0.680851 (-7460 5235);
PAINT MONO (-7460 5235);
FORCEPROP 0 LASTPIN (-7450 4825) $PN 80
J 2
(-7460 4835);
DISPLAY 0.680851 (-7460 4835);
PAINT MONO (-7460 4835);
FORCEPROP 0 LASTPIN (-7450 5275) $PN 215
J 2
(-7460 5285);
DISPLAY 0.680851 (-7460 5285);
PAINT MONO (-7460 5285);
FORCEPROP 0 LASTPIN (-7450 4875) $PN 225
J 2
(-7460 4885);
DISPLAY 0.680851 (-7460 4885);
PAINT MONO (-7460 4885);
FORCEPROP 0 LASTPIN (-7450 5325) $PN 72
J 2
(-7460 5335);
DISPLAY 0.680851 (-7460 5335);
PAINT MONO (-7460 5335);
FORCEPROP 0 LASTPIN (-7450 4925) $PN 82
J 2
(-7460 4935);
DISPLAY 0.680851 (-7460 4935);
PAINT MONO (-7460 4935);
FORCEPROP 0 LASTPIN (-7450 3575) $PN 51
J 2
(-7460 3585);
DISPLAY 0.680851 (-7460 3585);
PAINT MONO (-7460 3585);
FORCEPROP 0 LASTPIN (-7450 3125) $PN 96
J 2
(-7460 3135);
DISPLAY 0.680851 (-7460 3135);
PAINT MONO (-7460 3135);
FORCEPROP 0 LASTPIN (-7450 3625) $PN 53
J 2
(-7460 3635);
DISPLAY 0.680851 (-7460 3635);
PAINT MONO (-7460 3635);
FORCEPROP 0 LASTPIN (-7450 3175) $PN 98
J 2
(-7460 3185);
DISPLAY 0.680851 (-7460 3185);
PAINT MONO (-7460 3185);
FORCEPROP 0 LASTPIN (-7450 3675) $PN 196
J 2
(-7460 3685);
DISPLAY 0.680851 (-7460 3685);
PAINT MONO (-7460 3685);
FORCEPROP 0 LASTPIN (-7450 3225) $PN 241
J 2
(-7460 3235);
DISPLAY 0.680851 (-7460 3235);
PAINT MONO (-7460 3235);
FORCEPROP 0 LASTPIN (-7450 3725) $PN 198
J 2
(-7460 3735);
DISPLAY 0.680851 (-7460 3735);
PAINT MONO (-7460 3735);
FORCEPROP 0 LASTPIN (-7450 3275) $PN 243
J 2
(-7460 3285);
DISPLAY 0.680851 (-7460 3285);
PAINT MONO (-7460 3285);
FORCEPROP 0 LASTPIN (-7450 3775) $PN 58
J 2
(-7460 3785);
DISPLAY 0.680851 (-7460 3785);
PAINT MONO (-7460 3785);
FORCEPROP 0 LASTPIN (-7450 3325) $PN 89
J 2
(-7460 3335);
DISPLAY 0.680851 (-7460 3335);
PAINT MONO (-7460 3335);
FORCEPROP 0 LASTPIN (-7450 3825) $PN 60
J 2
(-7460 3835);
DISPLAY 0.680851 (-7460 3835);
PAINT MONO (-7460 3835);
FORCEPROP 0 LASTPIN (-7450 3375) $PN 91
J 2
(-7460 3385);
DISPLAY 0.680851 (-7460 3385);
PAINT MONO (-7460 3385);
FORCEPROP 0 LASTPIN (-7450 3875) $PN 203
J 2
(-7460 3885);
DISPLAY 0.680851 (-7460 3885);
PAINT MONO (-7460 3885);
FORCEPROP 0 LASTPIN (-7450 3425) $PN 234
J 2
(-7460 3435);
DISPLAY 0.680851 (-7460 3435);
PAINT MONO (-7460 3435);
FORCEPROP 0 LASTPIN (-7450 3925) $PN 205
J 2
(-7460 3935);
DISPLAY 0.680851 (-7460 3935);
PAINT MONO (-7460 3935);
FORCEPROP 0 LASTPIN (-7450 3475) $PN 236
J 2
(-7460 3485);
DISPLAY 0.680851 (-7460 3485);
PAINT MONO (-7460 3485);
FORCEPROP 0 LASTPIN (-7450 4025) $PN 218
J 2
(-7460 4035);
DISPLAY 0.680851 (-7460 4035);
PAINT MONO (-7460 4035);
FORCEPROP 0 LASTPIN (-7450 4075) $PN 217
J 2
(-7460 4085);
DISPLAY 0.680851 (-7460 4085);
PAINT MONO (-7460 4085);
FORCEPROP 0 LASTPIN (-7450 4325) $PN 64
J 2
(-7460 4335);
DISPLAY 0.680851 (-7460 4335);
PAINT MONO (-7460 4335);
FORCEPROP 0 LASTPIN (-7450 4175) $PN 84
J 2
(-7460 4185);
DISPLAY 0.680851 (-7460 4185);
PAINT MONO (-7460 4185);
FORCEPROP 0 LASTPIN (-7450 4375) $PN 209
J 2
(-7460 4385);
DISPLAY 0.680851 (-7460 4385);
PAINT MONO (-7460 4385);
FORCEPROP 0 LASTPIN (-7450 4225) $PN 229
J 2
(-7460 4235);
DISPLAY 0.680851 (-7460 4235);
PAINT MONO (-7460 4235);
FORCEPROP 0 LASTPIN (-6250 3775) $PN 7
J 0
(-6240 3785);
DISPLAY 0.680851 (-6240 3785);
PAINT MONO (-6240 3785);
FORCEPROP 0 LASTPIN (-6250 2125) $PN 100
J 0
(-6240 2135);
DISPLAY 0.680851 (-6240 2135);
PAINT MONO (-6240 2135);
FORCEPROP 0 LASTPIN (-6250 3825) $PN 9
J 0
(-6240 3835);
DISPLAY 0.680851 (-6240 3835);
PAINT MONO (-6240 3835);
FORCEPROP 0 LASTPIN (-6250 2175) $PN 102
J 0
(-6240 2185);
DISPLAY 0.680851 (-6240 2185);
PAINT MONO (-6240 2185);
FORCEPROP 0 LASTPIN (-6250 3875) $PN 152
J 0
(-6240 3885);
DISPLAY 0.680851 (-6240 3885);
PAINT MONO (-6240 3885);
FORCEPROP 0 LASTPIN (-6250 2225) $PN 245
J 0
(-6240 2235);
DISPLAY 0.680851 (-6240 2235);
PAINT MONO (-6240 2235);
FORCEPROP 0 LASTPIN (-6250 3925) $PN 154
J 0
(-6240 3935);
DISPLAY 0.680851 (-6240 3935);
PAINT MONO (-6240 3935);
FORCEPROP 0 LASTPIN (-6250 2275) $PN 247
J 0
(-6240 2285);
DISPLAY 0.680851 (-6240 2285);
PAINT MONO (-6240 2285);
FORCEPROP 0 LASTPIN (-6250 3975) $PN 14
J 0
(-6240 3985);
DISPLAY 0.680851 (-6240 3985);
PAINT MONO (-6240 3985);
FORCEPROP 0 LASTPIN (-6250 2325) $PN 107
J 0
(-6240 2335);
DISPLAY 0.680851 (-6240 2335);
PAINT MONO (-6240 2335);
FORCEPROP 0 LASTPIN (-6250 4025) $PN 16
J 0
(-6240 4035);
DISPLAY 0.680851 (-6240 4035);
PAINT MONO (-6240 4035);
FORCEPROP 0 LASTPIN (-6250 2375) $PN 109
J 0
(-6240 2385);
DISPLAY 0.680851 (-6240 2385);
PAINT MONO (-6240 2385);
FORCEPROP 0 LASTPIN (-6250 4075) $PN 159
J 0
(-6240 4085);
DISPLAY 0.680851 (-6240 4085);
PAINT MONO (-6240 4085);
FORCEPROP 0 LASTPIN (-6250 2425) $PN 252
J 0
(-6240 2435);
DISPLAY 0.680851 (-6240 2435);
PAINT MONO (-6240 2435);
FORCEPROP 0 LASTPIN (-6250 4125) $PN 161
J 0
(-6240 4135);
DISPLAY 0.680851 (-6240 4135);
PAINT MONO (-6240 4135);
FORCEPROP 0 LASTPIN (-6250 2475) $PN 254
J 0
(-6240 2485);
DISPLAY 0.680851 (-6240 2485);
PAINT MONO (-6240 2485);
FORCEPROP 0 LASTPIN (-6250 4175) $PN 18
J 0
(-6240 4185);
DISPLAY 0.680851 (-6240 4185);
PAINT MONO (-6240 4185);
FORCEPROP 0 LASTPIN (-6250 2525) $PN 111
J 0
(-6240 2535);
DISPLAY 0.680851 (-6240 2535);
PAINT MONO (-6240 2535);
FORCEPROP 0 LASTPIN (-6250 4225) $PN 20
J 0
(-6240 4235);
DISPLAY 0.680851 (-6240 4235);
PAINT MONO (-6240 4235);
FORCEPROP 0 LASTPIN (-6250 2575) $PN 113
J 0
(-6240 2585);
DISPLAY 0.680851 (-6240 2585);
PAINT MONO (-6240 2585);
FORCEPROP 0 LASTPIN (-6250 4275) $PN 163
J 0
(-6240 4285);
DISPLAY 0.680851 (-6240 4285);
PAINT MONO (-6240 4285);
FORCEPROP 0 LASTPIN (-6250 2625) $PN 256
J 0
(-6240 2635);
DISPLAY 0.680851 (-6240 2635);
PAINT MONO (-6240 2635);
FORCEPROP 0 LASTPIN (-6250 4325) $PN 165
J 0
(-6240 4335);
DISPLAY 0.680851 (-6240 4335);
PAINT MONO (-6240 4335);
FORCEPROP 0 LASTPIN (-6250 2675) $PN 258
J 0
(-6240 2685);
DISPLAY 0.680851 (-6240 2685);
PAINT MONO (-6240 2685);
FORCEPROP 0 LASTPIN (-6250 4375) $PN 25
J 0
(-6240 4385);
DISPLAY 0.680851 (-6240 4385);
PAINT MONO (-6240 4385);
FORCEPROP 0 LASTPIN (-6250 2725) $PN 118
J 0
(-6240 2735);
DISPLAY 0.680851 (-6240 2735);
PAINT MONO (-6240 2735);
FORCEPROP 0 LASTPIN (-6250 4425) $PN 27
J 0
(-6240 4435);
DISPLAY 0.680851 (-6240 4435);
PAINT MONO (-6240 4435);
FORCEPROP 0 LASTPIN (-6250 2775) $PN 120
J 0
(-6240 2785);
DISPLAY 0.680851 (-6240 2785);
PAINT MONO (-6240 2785);
FORCEPROP 0 LASTPIN (-6250 4475) $PN 170
J 0
(-6240 4485);
DISPLAY 0.680851 (-6240 4485);
PAINT MONO (-6240 4485);
FORCEPROP 0 LASTPIN (-6250 2825) $PN 263
J 0
(-6240 2835);
DISPLAY 0.680851 (-6240 2835);
PAINT MONO (-6240 2835);
FORCEPROP 0 LASTPIN (-6250 4525) $PN 172
J 0
(-6240 4535);
DISPLAY 0.680851 (-6240 4535);
PAINT MONO (-6240 4535);
FORCEPROP 0 LASTPIN (-6250 2875) $PN 265
J 0
(-6240 2885);
DISPLAY 0.680851 (-6240 2885);
PAINT MONO (-6240 2885);
FORCEPROP 0 LASTPIN (-6250 4575) $PN 29
J 0
(-6240 4585);
DISPLAY 0.680851 (-6240 4585);
PAINT MONO (-6240 4585);
FORCEPROP 0 LASTPIN (-6250 2925) $PN 122
J 0
(-6240 2935);
DISPLAY 0.680851 (-6240 2935);
PAINT MONO (-6240 2935);
FORCEPROP 0 LASTPIN (-6250 4625) $PN 31
J 0
(-6240 4635);
DISPLAY 0.680851 (-6240 4635);
PAINT MONO (-6240 4635);
FORCEPROP 0 LASTPIN (-6250 2975) $PN 124
J 0
(-6240 2985);
DISPLAY 0.680851 (-6240 2985);
PAINT MONO (-6240 2985);
FORCEPROP 0 LASTPIN (-6250 4675) $PN 174
J 0
(-6240 4685);
DISPLAY 0.680851 (-6240 4685);
PAINT MONO (-6240 4685);
FORCEPROP 0 LASTPIN (-6250 3025) $PN 267
J 0
(-6240 3035);
DISPLAY 0.680851 (-6240 3035);
PAINT MONO (-6240 3035);
FORCEPROP 0 LASTPIN (-6250 4725) $PN 176
J 0
(-6240 4735);
DISPLAY 0.680851 (-6240 4735);
PAINT MONO (-6240 4735);
FORCEPROP 0 LASTPIN (-6250 3075) $PN 269
J 0
(-6240 3085);
DISPLAY 0.680851 (-6240 3085);
PAINT MONO (-6240 3085);
FORCEPROP 0 LASTPIN (-6250 4775) $PN 36
J 0
(-6240 4785);
DISPLAY 0.680851 (-6240 4785);
PAINT MONO (-6240 4785);
FORCEPROP 0 LASTPIN (-6250 3125) $PN 129
J 0
(-6240 3135);
DISPLAY 0.680851 (-6240 3135);
PAINT MONO (-6240 3135);
FORCEPROP 0 LASTPIN (-6250 4825) $PN 38
J 0
(-6240 4835);
DISPLAY 0.680851 (-6240 4835);
PAINT MONO (-6240 4835);
FORCEPROP 0 LASTPIN (-6250 3175) $PN 131
J 0
(-6240 3185);
DISPLAY 0.680851 (-6240 3185);
PAINT MONO (-6240 3185);
FORCEPROP 0 LASTPIN (-6250 4875) $PN 181
J 0
(-6240 4885);
DISPLAY 0.680851 (-6240 4885);
PAINT MONO (-6240 4885);
FORCEPROP 0 LASTPIN (-6250 3225) $PN 274
J 0
(-6240 3235);
DISPLAY 0.680851 (-6240 3235);
PAINT MONO (-6240 3235);
FORCEPROP 0 LASTPIN (-6250 4925) $PN 183
J 0
(-6240 4935);
DISPLAY 0.680851 (-6240 4935);
PAINT MONO (-6240 4935);
FORCEPROP 0 LASTPIN (-6250 3275) $PN 276
J 0
(-6240 3285);
DISPLAY 0.680851 (-6240 3285);
PAINT MONO (-6240 3285);
FORCEPROP 0 LASTPIN (-6250 4975) $PN 40
J 0
(-6240 4985);
DISPLAY 0.680851 (-6240 4985);
PAINT MONO (-6240 4985);
FORCEPROP 0 LASTPIN (-6250 3325) $PN 133
J 0
(-6240 3335);
DISPLAY 0.680851 (-6240 3335);
PAINT MONO (-6240 3335);
FORCEPROP 0 LASTPIN (-6250 5025) $PN 42
J 0
(-6240 5035);
DISPLAY 0.680851 (-6240 5035);
PAINT MONO (-6240 5035);
FORCEPROP 0 LASTPIN (-6250 3375) $PN 135
J 0
(-6240 3385);
DISPLAY 0.680851 (-6240 3385);
PAINT MONO (-6240 3385);
FORCEPROP 0 LASTPIN (-6250 5075) $PN 185
J 0
(-6240 5085);
DISPLAY 0.680851 (-6240 5085);
PAINT MONO (-6240 5085);
FORCEPROP 0 LASTPIN (-6250 3425) $PN 278
J 0
(-6240 3435);
DISPLAY 0.680851 (-6240 3435);
PAINT MONO (-6240 3435);
FORCEPROP 0 LASTPIN (-6250 5125) $PN 187
J 0
(-6240 5135);
DISPLAY 0.680851 (-6240 5135);
PAINT MONO (-6240 5135);
FORCEPROP 0 LASTPIN (-6250 3475) $PN 280
J 0
(-6240 3485);
DISPLAY 0.680851 (-6240 3485);
PAINT MONO (-6240 3485);
FORCEPROP 0 LASTPIN (-6250 5175) $PN 47
J 0
(-6240 5185);
DISPLAY 0.680851 (-6240 5185);
PAINT MONO (-6240 5185);
FORCEPROP 0 LASTPIN (-6250 3525) $PN 140
J 0
(-6240 3535);
DISPLAY 0.680851 (-6240 3535);
PAINT MONO (-6240 3535);
FORCEPROP 0 LASTPIN (-6250 5225) $PN 49
J 0
(-6240 5235);
DISPLAY 0.680851 (-6240 5235);
PAINT MONO (-6240 5235);
FORCEPROP 0 LASTPIN (-6250 3575) $PN 142
J 0
(-6240 3585);
DISPLAY 0.680851 (-6240 3585);
PAINT MONO (-6240 3585);
FORCEPROP 0 LASTPIN (-6250 5275) $PN 192
J 0
(-6240 5285);
DISPLAY 0.680851 (-6240 5285);
PAINT MONO (-6240 5285);
FORCEPROP 0 LASTPIN (-6250 3625) $PN 285
J 0
(-6240 3635);
DISPLAY 0.680851 (-6240 3635);
PAINT MONO (-6240 3635);
FORCEPROP 0 LASTPIN (-6250 5325) $PN 194
J 0
(-6240 5335);
DISPLAY 0.680851 (-6240 5335);
PAINT MONO (-6240 5335);
FORCEPROP 0 LASTPIN (-6250 3675) $PN 287
J 0
(-6240 3685);
DISPLAY 0.680851 (-6240 3685);
PAINT MONO (-6240 3685);
FORCEPROP 0 LASTPIN (-7450 2825) $PN 148
J 2
(-7460 2835);
DISPLAY 0.680851 (-7460 2835);
PAINT MONO (-7460 2835);
FORCEPROP 0 LASTPIN (-7450 2725) $PN 4
J 2
(-7460 2735);
DISPLAY 0.680851 (-7460 2735);
PAINT MONO (-7460 2735);
FORCEPROP 0 LASTPIN (-7450 2775) $PN 5
J 2
(-7460 2785);
DISPLAY 0.680851 (-7460 2785);
PAINT MONO (-7460 2785);
FORCEPROP 0 LASTPIN (-7450 1925) $PN 86
J 2
(-7460 1935);
DISPLAY 0.680851 (-7460 1935);
PAINT MONO (-7460 1935);
FORCEPROP 0 LASTPIN (-7450 1875) $PN 87
J 2
(-7460 1885);
DISPLAY 0.680851 (-7460 1885);
PAINT MONO (-7460 1885);
FORCEPROP 0 LASTPIN (-7450 4525) $PN 74
J 2
(-7460 4535);
DISPLAY 0.680851 (-7460 4535);
PAINT MONO (-7460 4535);
FORCEPROP 0 LASTPIN (-7450 4475) $PN 227
J 2
(-7460 4485);
DISPLAY 0.680851 (-7460 4485);
PAINT MONO (-7460 4485);
FORCEPROP 0 LASTPIN (-7450 2475) $PN 147
J 2
(-7460 2485);
DISPLAY 0.680851 (-7460 2485);
PAINT MONO (-7460 2485);
FORCEPROP 0 LASTPIN (-7450 3025) $PN 207
J 2
(-7460 3035);
DISPLAY 0.680851 (-7460 3035);
PAINT MONO (-7460 3035);
FORCEPROP 0 LASTPIN (-7450 2075) $PN 2
J 2
(-7460 2085);
DISPLAY 0.680851 (-7460 2085);
PAINT MONO (-7460 2085);
FORCEPROP 0 LASTPIN (-7450 2125) $PN 144
J 2
(-7460 2135);
DISPLAY 0.680851 (-7460 2135);
PAINT MONO (-7460 2135);
FORCEPROP 0 LASTPIN (-7450 2175) $PN 149
J 2
(-7460 2185);
DISPLAY 0.680851 (-7460 2185);
PAINT MONO (-7460 2185);
FORCEPROP 0 LASTPIN (-7450 2225) $PN 150
J 2
(-7460 2235);
DISPLAY 0.680851 (-7460 2235);
PAINT MONO (-7460 2235);
FORCEPROP 0 LASTPIN (-7450 2275) $PN 220
J 2
(-7460 2285);
DISPLAY 0.680851 (-7460 2285);
PAINT MONO (-7460 2285);
FORCEPROP 0 LASTPIN (-7450 2325) $PN 231
J 2
(-7460 2335);
DISPLAY 0.680851 (-7460 2335);
PAINT MONO (-7460 2335);
FORCEPROP 0 LASTPIN (-7450 2375) $PN 232
J 2
(-7460 2385);
DISPLAY 0.680851 (-7460 2385);
PAINT MONO (-7460 2385);
FORCEPROP 0 LASTPIN (-7450 2875) $PN 3
J 2
(-7460 2885);
DISPLAY 0.680851 (-7460 2885);
PAINT MONO (-7460 2885);
FORCEPROP 2 LAST PART_TYPE SMLF
J 0
(-7300 5750);
DISPLAY 1.021277 (-7300 5750);
FORCEPROP 1 LAST MATERIAL IO
J 0
(-7300 5500);
DISPLAY 0.468085 (-7300 5500);
PAINT SKYBLUE (-7300 5500);
FORCEPROP 2 LAST VALUE SCONN288_DDR506112002KQ
J 0
(-7300 5700);
DISPLAY 0.489362 (-7300 5700);
PAINT SKYBLUE (-7300 5700);
FORCEPROP 1 LAST CDS_LMAN_SYM_OUTLINE -450,1900,450,-1850
J 0
(-6850 3575);
DISPLAY 0.468085 (-6850 3575);
PAINT GREEN (-6850 3575);
DISPLAY INVISIBLE (-6850 3575);
FORCEPROP 1 LAST NEEDS_NO_SIZE TRUE
J 0
(-6850 3575);
DISPLAY 0.723404 (-6850 3575);
PAINT GREEN (-6850 3575);
DISPLAY INVISIBLE (-6850 3575);
FORCEPROP 2 LAST CDS_LIB pure_quanta
J 0
(-6850 3575);
DISPLAY INVISIBLE (-6850 3575);
FORCEPROP 1 LAST PATH I22
J 0
(-6850 3575);
DISPLAY 0.723404 (-6850 3575);
PAINT GREEN (-6850 3575);
DISPLAY INVISIBLE (-6850 3575);
FORCEPROP 1 LAST PART_NUMBER DFHST8FS479
J 0
(-7300 5575);
DISPLAY 0.468085 (-7300 5575);
PAINT SKYBLUE (-7300 5575);
DISPLAY INVISIBLE (-7300 5575);
FORCEADD TAP..1
(-3275 3100);
FORCEPROP 3 LASTPIN (-3325 3100) SIG_NAME M_K_CPU1_SB_DQS_DN<6>
J 0
(-3315 3110);
DISPLAY 0.659574 (-3315 3110);
PAINT MONO (-3315 3110);
DISPLAY INVISIBLE (-3315 3110);
FORCEPROP 1 LASTPIN (-3325 3100) BN 6
J 0
(-3337 3108);
DISPLAY 0.489362 (-3337 3108);
PAINT GREEN (-3337 3108);
FORCEPROP 2 LAST CDS_LIB mstr_standard
J 0
(-3275 3100);
DISPLAY 0.723404 (-3275 3100);
PAINT MONO (-3275 3100);
DISPLAY INVISIBLE (-3275 3100);
FORCEPROP 1 LAST BODY_TYPE PLUMBING
J 0
(-3275 3150);
DISPLAY 0.872340 (-3275 3150);
PAINT GREEN (-3275 3150);
DISPLAY INVISIBLE (-3275 3150);
FORCEPROP 1 LAST HDL_TAP TRUE
J 0
(-2950 2975);
DISPLAY 0.872340 (-2950 2975);
DISPLAY INVISIBLE (-2950 2975);
FORCEPROP 1 LAST PATH I220
J 0
(-3277 3100);
DISPLAY 0.872340 (-3277 3100);
PAINT GREEN (-3277 3100);
DISPLAY INVISIBLE (-3277 3100);
FORCEADD TAP..1
(-3475 3250);
FORCEPROP 3 LASTPIN (-3525 3250) SIG_NAME M_K_CPU1_SB_DQS_DP<7>
J 0
(-3515 3260);
DISPLAY 0.659574 (-3515 3260);
PAINT MONO (-3515 3260);
DISPLAY INVISIBLE (-3515 3260);
FORCEPROP 1 LASTPIN (-3525 3250) BN 7
J 0
(-3537 3258);
DISPLAY 0.489362 (-3537 3258);
PAINT GREEN (-3537 3258);
FORCEPROP 2 LAST CDS_LIB mstr_standard
J 0
(-3475 3250);
DISPLAY 0.723404 (-3475 3250);
PAINT MONO (-3475 3250);
DISPLAY INVISIBLE (-3475 3250);
FORCEPROP 1 LAST BODY_TYPE PLUMBING
J 0
(-3475 3300);
DISPLAY 0.872340 (-3475 3300);
PAINT GREEN (-3475 3300);
DISPLAY INVISIBLE (-3475 3300);
FORCEPROP 1 LAST HDL_TAP TRUE
J 0
(-3150 3125);
DISPLAY 0.872340 (-3150 3125);
DISPLAY INVISIBLE (-3150 3125);
FORCEPROP 1 LAST PATH I221
J 0
(-3477 3250);
DISPLAY 0.872340 (-3477 3250);
PAINT GREEN (-3477 3250);
DISPLAY INVISIBLE (-3477 3250);
FORCEADD TAP..1
(-3475 3150);
FORCEPROP 3 LASTPIN (-3525 3150) SIG_NAME M_K_CPU1_SB_DQS_DP<6>
J 0
(-3515 3160);
DISPLAY 0.659574 (-3515 3160);
PAINT MONO (-3515 3160);
DISPLAY INVISIBLE (-3515 3160);
FORCEPROP 1 LASTPIN (-3525 3150) BN 6
J 0
(-3537 3158);
DISPLAY 0.489362 (-3537 3158);
PAINT GREEN (-3537 3158);
FORCEPROP 2 LAST CDS_LIB mstr_standard
J 0
(-3475 3150);
DISPLAY 0.723404 (-3475 3150);
PAINT MONO (-3475 3150);
DISPLAY INVISIBLE (-3475 3150);
FORCEPROP 1 LAST BODY_TYPE PLUMBING
J 0
(-3475 3200);
DISPLAY 0.872340 (-3475 3200);
PAINT GREEN (-3475 3200);
DISPLAY INVISIBLE (-3475 3200);
FORCEPROP 1 LAST HDL_TAP TRUE
J 0
(-3150 3025);
DISPLAY 0.872340 (-3150 3025);
DISPLAY INVISIBLE (-3150 3025);
FORCEPROP 1 LAST PATH I222
J 0
(-3477 3150);
DISPLAY 0.872340 (-3477 3150);
PAINT GREEN (-3477 3150);
DISPLAY INVISIBLE (-3477 3150);
FORCEADD TAP..1
(-3275 3000);
FORCEPROP 3 LASTPIN (-3325 3000) SIG_NAME M_K_CPU1_SB_DQS_DN<5>
J 0
(-3315 3010);
DISPLAY 0.659574 (-3315 3010);
PAINT MONO (-3315 3010);
DISPLAY INVISIBLE (-3315 3010);
FORCEPROP 1 LASTPIN (-3325 3000) BN 5
J 0
(-3337 3008);
DISPLAY 0.489362 (-3337 3008);
PAINT GREEN (-3337 3008);
FORCEPROP 2 LAST CDS_LIB mstr_standard
J 0
(-3275 3000);
DISPLAY 0.723404 (-3275 3000);
PAINT MONO (-3275 3000);
DISPLAY INVISIBLE (-3275 3000);
FORCEPROP 1 LAST BODY_TYPE PLUMBING
J 0
(-3275 3050);
DISPLAY 0.872340 (-3275 3050);
PAINT GREEN (-3275 3050);
DISPLAY INVISIBLE (-3275 3050);
FORCEPROP 1 LAST HDL_TAP TRUE
J 0
(-2950 2875);
DISPLAY 0.872340 (-2950 2875);
DISPLAY INVISIBLE (-2950 2875);
FORCEPROP 1 LAST PATH I223
J 0
(-3277 3000);
DISPLAY 0.872340 (-3277 3000);
PAINT GREEN (-3277 3000);
DISPLAY INVISIBLE (-3277 3000);
FORCEADD TAP..1
(-3275 2900);
FORCEPROP 3 LASTPIN (-3325 2900) SIG_NAME M_K_CPU1_SB_DQS_DN<4>
J 0
(-3315 2910);
DISPLAY 0.659574 (-3315 2910);
PAINT MONO (-3315 2910);
DISPLAY INVISIBLE (-3315 2910);
FORCEPROP 1 LASTPIN (-3325 2900) BN 4
J 0
(-3337 2908);
DISPLAY 0.489362 (-3337 2908);
PAINT GREEN (-3337 2908);
FORCEPROP 2 LAST CDS_LIB mstr_standard
J 0
(-3275 2900);
DISPLAY 0.723404 (-3275 2900);
PAINT MONO (-3275 2900);
DISPLAY INVISIBLE (-3275 2900);
FORCEPROP 1 LAST BODY_TYPE PLUMBING
J 0
(-3275 2950);
DISPLAY 0.872340 (-3275 2950);
PAINT GREEN (-3275 2950);
DISPLAY INVISIBLE (-3275 2950);
FORCEPROP 1 LAST HDL_TAP TRUE
J 0
(-2950 2775);
DISPLAY 0.872340 (-2950 2775);
DISPLAY INVISIBLE (-2950 2775);
FORCEPROP 1 LAST PATH I224
J 0
(-3277 2900);
DISPLAY 0.872340 (-3277 2900);
PAINT GREEN (-3277 2900);
DISPLAY INVISIBLE (-3277 2900);
FORCEADD TAP..1
(-3475 2950);
FORCEPROP 3 LASTPIN (-3525 2950) SIG_NAME M_K_CPU1_SB_DQS_DP<4>
J 0
(-3515 2960);
DISPLAY 0.659574 (-3515 2960);
PAINT MONO (-3515 2960);
DISPLAY INVISIBLE (-3515 2960);
FORCEPROP 1 LASTPIN (-3525 2950) BN 4
J 0
(-3537 2958);
DISPLAY 0.489362 (-3537 2958);
PAINT GREEN (-3537 2958);
FORCEPROP 2 LAST CDS_LIB mstr_standard
J 0
(-3475 2950);
DISPLAY 0.723404 (-3475 2950);
PAINT MONO (-3475 2950);
DISPLAY INVISIBLE (-3475 2950);
FORCEPROP 1 LAST BODY_TYPE PLUMBING
J 0
(-3475 3000);
DISPLAY 0.872340 (-3475 3000);
PAINT GREEN (-3475 3000);
DISPLAY INVISIBLE (-3475 3000);
FORCEPROP 1 LAST HDL_TAP TRUE
J 0
(-3150 2825);
DISPLAY 0.872340 (-3150 2825);
DISPLAY INVISIBLE (-3150 2825);
FORCEPROP 1 LAST PATH I225
J 0
(-3477 2950);
DISPLAY 0.872340 (-3477 2950);
PAINT GREEN (-3477 2950);
DISPLAY INVISIBLE (-3477 2950);
FORCEADD TAP..1
(-3475 3050);
FORCEPROP 3 LASTPIN (-3525 3050) SIG_NAME M_K_CPU1_SB_DQS_DP<5>
J 0
(-3515 3060);
DISPLAY 0.659574 (-3515 3060);
PAINT MONO (-3515 3060);
DISPLAY INVISIBLE (-3515 3060);
FORCEPROP 1 LASTPIN (-3525 3050) BN 5
J 0
(-3537 3058);
DISPLAY 0.489362 (-3537 3058);
PAINT GREEN (-3537 3058);
FORCEPROP 2 LAST CDS_LIB mstr_standard
J 0
(-3475 3050);
DISPLAY 0.723404 (-3475 3050);
PAINT MONO (-3475 3050);
DISPLAY INVISIBLE (-3475 3050);
FORCEPROP 1 LAST BODY_TYPE PLUMBING
J 0
(-3475 3100);
DISPLAY 0.872340 (-3475 3100);
PAINT GREEN (-3475 3100);
DISPLAY INVISIBLE (-3475 3100);
FORCEPROP 1 LAST HDL_TAP TRUE
J 0
(-3150 2925);
DISPLAY 0.872340 (-3150 2925);
DISPLAY INVISIBLE (-3150 2925);
FORCEPROP 1 LAST PATH I226
J 0
(-3477 3050);
DISPLAY 0.872340 (-3477 3050);
PAINT GREEN (-3477 3050);
DISPLAY INVISIBLE (-3477 3050);
FORCEADD TAP..1
(-3475 2850);
FORCEPROP 3 LASTPIN (-3525 2850) SIG_NAME M_K_CPU1_SB_DQS_DP<3>
J 0
(-3515 2860);
DISPLAY 0.659574 (-3515 2860);
PAINT MONO (-3515 2860);
DISPLAY INVISIBLE (-3515 2860);
FORCEPROP 1 LASTPIN (-3525 2850) BN 3
J 0
(-3537 2858);
DISPLAY 0.489362 (-3537 2858);
PAINT GREEN (-3537 2858);
FORCEPROP 2 LAST CDS_LIB mstr_standard
J 0
(-3475 2850);
DISPLAY 0.723404 (-3475 2850);
PAINT MONO (-3475 2850);
DISPLAY INVISIBLE (-3475 2850);
FORCEPROP 1 LAST BODY_TYPE PLUMBING
J 0
(-3475 2900);
DISPLAY 0.872340 (-3475 2900);
PAINT GREEN (-3475 2900);
DISPLAY INVISIBLE (-3475 2900);
FORCEPROP 1 LAST HDL_TAP TRUE
J 0
(-3150 2725);
DISPLAY 0.872340 (-3150 2725);
DISPLAY INVISIBLE (-3150 2725);
FORCEPROP 1 LAST PATH I227
J 0
(-3477 2850);
DISPLAY 0.872340 (-3477 2850);
PAINT GREEN (-3477 2850);
DISPLAY INVISIBLE (-3477 2850);
FORCEADD TAP..1
(-3275 2700);
FORCEPROP 3 LASTPIN (-3325 2700) SIG_NAME M_K_CPU1_SB_DQS_DN<2>
J 0
(-3315 2710);
DISPLAY 0.659574 (-3315 2710);
PAINT MONO (-3315 2710);
DISPLAY INVISIBLE (-3315 2710);
FORCEPROP 1 LASTPIN (-3325 2700) BN 2
J 0
(-3337 2708);
DISPLAY 0.489362 (-3337 2708);
PAINT GREEN (-3337 2708);
FORCEPROP 2 LAST CDS_LIB mstr_standard
J 0
(-3275 2700);
DISPLAY 0.723404 (-3275 2700);
PAINT MONO (-3275 2700);
DISPLAY INVISIBLE (-3275 2700);
FORCEPROP 1 LAST BODY_TYPE PLUMBING
J 0
(-3275 2750);
DISPLAY 0.872340 (-3275 2750);
PAINT GREEN (-3275 2750);
DISPLAY INVISIBLE (-3275 2750);
FORCEPROP 1 LAST HDL_TAP TRUE
J 0
(-2950 2575);
DISPLAY 0.872340 (-2950 2575);
DISPLAY INVISIBLE (-2950 2575);
FORCEPROP 1 LAST PATH I228
J 0
(-3277 2700);
DISPLAY 0.872340 (-3277 2700);
PAINT GREEN (-3277 2700);
DISPLAY INVISIBLE (-3277 2700);
FORCEADD TAP..1
(-3275 2800);
FORCEPROP 3 LASTPIN (-3325 2800) SIG_NAME M_K_CPU1_SB_DQS_DN<3>
J 0
(-3315 2810);
DISPLAY 0.659574 (-3315 2810);
PAINT MONO (-3315 2810);
DISPLAY INVISIBLE (-3315 2810);
FORCEPROP 1 LASTPIN (-3325 2800) BN 3
J 0
(-3337 2808);
DISPLAY 0.489362 (-3337 2808);
PAINT GREEN (-3337 2808);
FORCEPROP 2 LAST CDS_LIB mstr_standard
J 0
(-3275 2800);
DISPLAY 0.723404 (-3275 2800);
PAINT MONO (-3275 2800);
DISPLAY INVISIBLE (-3275 2800);
FORCEPROP 1 LAST BODY_TYPE PLUMBING
J 0
(-3275 2850);
DISPLAY 0.872340 (-3275 2850);
PAINT GREEN (-3275 2850);
DISPLAY INVISIBLE (-3275 2850);
FORCEPROP 1 LAST HDL_TAP TRUE
J 0
(-2950 2675);
DISPLAY 0.872340 (-2950 2675);
DISPLAY INVISIBLE (-2950 2675);
FORCEPROP 1 LAST PATH I229
J 0
(-3277 2800);
DISPLAY 0.872340 (-3277 2800);
PAINT GREEN (-3277 2800);
DISPLAY INVISIBLE (-3277 2800);
FORCEADD TAP..1
R 2
(-7700 3125);
FORCEPROP 3 LASTPIN (-7650 3125) SIG_NAME M_K_CPU1_SB_CB<0>
J 0
(-7640 3135);
DISPLAY 0.659574 (-7640 3135);
PAINT MONO (-7640 3135);
DISPLAY INVISIBLE (-7640 3135);
FORCEPROP 1 LASTPIN (-7650 3125) BN 0
J 2
(-7638 3133);
DISPLAY 0.489362 (-7638 3133);
PAINT GREEN (-7638 3133);
FORCEPROP 2 LAST CDS_LIB mstr_standard
J 0
(-7700 3125);
DISPLAY 0.723404 (-7700 3125);
PAINT MONO (-7700 3125);
DISPLAY INVISIBLE (-7700 3125);
FORCEPROP 1 LAST BODY_TYPE PLUMBING
J 2
(-7700 3175);
DISPLAY 0.872340 (-7700 3175);
PAINT GREEN (-7700 3175);
DISPLAY INVISIBLE (-7700 3175);
FORCEPROP 1 LAST HDL_TAP TRUE
J 2
(-8025 3000);
DISPLAY 0.872340 (-8025 3000);
DISPLAY INVISIBLE (-8025 3000);
FORCEPROP 1 LAST PATH I23
J 2
(-7698 3125);
DISPLAY 0.872340 (-7698 3125);
PAINT GREEN (-7698 3125);
DISPLAY INVISIBLE (-7698 3125);
FORCEADD TAP..1
(-3275 2600);
FORCEPROP 3 LASTPIN (-3325 2600) SIG_NAME M_K_CPU1_SB_DQS_DN<1>
J 0
(-3315 2610);
DISPLAY 0.659574 (-3315 2610);
PAINT MONO (-3315 2610);
DISPLAY INVISIBLE (-3315 2610);
FORCEPROP 1 LASTPIN (-3325 2600) BN 1
J 0
(-3337 2608);
DISPLAY 0.489362 (-3337 2608);
PAINT GREEN (-3337 2608);
FORCEPROP 2 LAST CDS_LIB mstr_standard
J 0
(-3275 2600);
DISPLAY 0.723404 (-3275 2600);
PAINT MONO (-3275 2600);
DISPLAY INVISIBLE (-3275 2600);
FORCEPROP 1 LAST BODY_TYPE PLUMBING
J 0
(-3275 2650);
DISPLAY 0.872340 (-3275 2650);
PAINT GREEN (-3275 2650);
DISPLAY INVISIBLE (-3275 2650);
FORCEPROP 1 LAST HDL_TAP TRUE
J 0
(-2950 2475);
DISPLAY 0.872340 (-2950 2475);
DISPLAY INVISIBLE (-2950 2475);
FORCEPROP 1 LAST PATH I230
J 0
(-3277 2600);
DISPLAY 0.872340 (-3277 2600);
PAINT GREEN (-3277 2600);
DISPLAY INVISIBLE (-3277 2600);
FORCEADD TAP..1
(-3475 2750);
FORCEPROP 3 LASTPIN (-3525 2750) SIG_NAME M_K_CPU1_SB_DQS_DP<2>
J 0
(-3515 2760);
DISPLAY 0.659574 (-3515 2760);
PAINT MONO (-3515 2760);
DISPLAY INVISIBLE (-3515 2760);
FORCEPROP 1 LASTPIN (-3525 2750) BN 2
J 0
(-3537 2758);
DISPLAY 0.489362 (-3537 2758);
PAINT GREEN (-3537 2758);
FORCEPROP 2 LAST CDS_LIB mstr_standard
J 0
(-3475 2750);
DISPLAY 0.723404 (-3475 2750);
PAINT MONO (-3475 2750);
DISPLAY INVISIBLE (-3475 2750);
FORCEPROP 1 LAST BODY_TYPE PLUMBING
J 0
(-3475 2800);
DISPLAY 0.872340 (-3475 2800);
PAINT GREEN (-3475 2800);
DISPLAY INVISIBLE (-3475 2800);
FORCEPROP 1 LAST HDL_TAP TRUE
J 0
(-3150 2625);
DISPLAY 0.872340 (-3150 2625);
DISPLAY INVISIBLE (-3150 2625);
FORCEPROP 1 LAST PATH I231
J 0
(-3477 2750);
DISPLAY 0.872340 (-3477 2750);
PAINT GREEN (-3477 2750);
DISPLAY INVISIBLE (-3477 2750);
FORCEADD TAP..1
(-3475 2650);
FORCEPROP 3 LASTPIN (-3525 2650) SIG_NAME M_K_CPU1_SB_DQS_DP<1>
J 0
(-3515 2660);
DISPLAY 0.659574 (-3515 2660);
PAINT MONO (-3515 2660);
DISPLAY INVISIBLE (-3515 2660);
FORCEPROP 1 LASTPIN (-3525 2650) BN 1
J 0
(-3537 2658);
DISPLAY 0.489362 (-3537 2658);
PAINT GREEN (-3537 2658);
FORCEPROP 2 LAST CDS_LIB mstr_standard
J 0
(-3475 2650);
DISPLAY 0.723404 (-3475 2650);
PAINT MONO (-3475 2650);
DISPLAY INVISIBLE (-3475 2650);
FORCEPROP 1 LAST BODY_TYPE PLUMBING
J 0
(-3475 2700);
DISPLAY 0.872340 (-3475 2700);
PAINT GREEN (-3475 2700);
DISPLAY INVISIBLE (-3475 2700);
FORCEPROP 1 LAST HDL_TAP TRUE
J 0
(-3150 2525);
DISPLAY 0.872340 (-3150 2525);
DISPLAY INVISIBLE (-3150 2525);
FORCEPROP 1 LAST PATH I232
J 0
(-3477 2650);
DISPLAY 0.872340 (-3477 2650);
PAINT GREEN (-3477 2650);
DISPLAY INVISIBLE (-3477 2650);
FORCEADD TAP..1
(-3475 2550);
FORCEPROP 3 LASTPIN (-3525 2550) SIG_NAME M_K_CPU1_SB_DQS_DP<0>
J 0
(-3515 2560);
DISPLAY 0.659574 (-3515 2560);
PAINT MONO (-3515 2560);
DISPLAY INVISIBLE (-3515 2560);
FORCEPROP 1 LASTPIN (-3525 2550) BN 0
J 0
(-3537 2558);
DISPLAY 0.489362 (-3537 2558);
PAINT GREEN (-3537 2558);
FORCEPROP 2 LAST CDS_LIB mstr_standard
J 0
(-3475 2550);
DISPLAY 0.723404 (-3475 2550);
PAINT MONO (-3475 2550);
DISPLAY INVISIBLE (-3475 2550);
FORCEPROP 1 LAST BODY_TYPE PLUMBING
J 0
(-3475 2600);
DISPLAY 0.872340 (-3475 2600);
PAINT GREEN (-3475 2600);
DISPLAY INVISIBLE (-3475 2600);
FORCEPROP 1 LAST HDL_TAP TRUE
J 0
(-3150 2425);
DISPLAY 0.872340 (-3150 2425);
DISPLAY INVISIBLE (-3150 2425);
FORCEPROP 1 LAST PATH I233
J 0
(-3477 2550);
DISPLAY 0.872340 (-3477 2550);
PAINT GREEN (-3477 2550);
DISPLAY INVISIBLE (-3477 2550);
FORCEADD TAP..1
(-3275 2500);
FORCEPROP 3 LASTPIN (-3325 2500) SIG_NAME M_K_CPU1_SB_DQS_DN<0>
J 0
(-3315 2510);
DISPLAY 0.659574 (-3315 2510);
PAINT MONO (-3315 2510);
DISPLAY INVISIBLE (-3315 2510);
FORCEPROP 1 LASTPIN (-3325 2500) BN 0
J 0
(-3337 2508);
DISPLAY 0.489362 (-3337 2508);
PAINT GREEN (-3337 2508);
FORCEPROP 2 LAST CDS_LIB mstr_standard
J 0
(-3275 2500);
DISPLAY 0.723404 (-3275 2500);
PAINT MONO (-3275 2500);
DISPLAY INVISIBLE (-3275 2500);
FORCEPROP 1 LAST BODY_TYPE PLUMBING
J 0
(-3275 2550);
DISPLAY 0.872340 (-3275 2550);
PAINT GREEN (-3275 2550);
DISPLAY INVISIBLE (-3275 2550);
FORCEPROP 1 LAST HDL_TAP TRUE
J 0
(-2950 2375);
DISPLAY 0.872340 (-2950 2375);
DISPLAY INVISIBLE (-2950 2375);
FORCEPROP 1 LAST PATH I234
J 0
(-3277 2500);
DISPLAY 0.872340 (-3277 2500);
PAINT GREEN (-3277 2500);
DISPLAY INVISIBLE (-3277 2500);
FORCEADD SCONN288_DDR506112002KQ..2
(-4425 3500);
FORCEPROP 1 LAST LOCATION J99
J 0
(-5025 4825);
DISPLAY 0.468085 (-5025 4825);
PAINT SKYBLUE (-5025 4825);
FORCEPROP 0 LAST $SEC 2
J 0
(-4875 4975);
DISPLAY 0.680851 (-4875 4975);
PAINT MONO (-4875 4975);
DISPLAY INVISIBLE (-4875 4975);
FORCEPROP 0 LAST CDS_SEC 2
J 0
(-4875 4975);
DISPLAY 1.021277 (-4875 4975);
DISPLAY INVISIBLE (-4875 4975);
FORCEPROP 0 LASTPIN (-3675 3550) $PN 12
J 0
(-3665 3560);
DISPLAY 0.680851 (-3665 3560);
PAINT MONO (-3665 3560);
FORCEPROP 0 LASTPIN (-3675 3600) $PN 11
J 0
(-3665 3610);
DISPLAY 0.680851 (-3665 3610);
PAINT MONO (-3665 3610);
FORCEPROP 0 LASTPIN (-3675 2500) $PN 105
J 0
(-3665 2510);
DISPLAY 0.680851 (-3665 2510);
PAINT MONO (-3665 2510);
FORCEPROP 0 LASTPIN (-3675 2550) $PN 104
J 0
(-3665 2560);
DISPLAY 0.680851 (-3665 2560);
PAINT MONO (-3665 2560);
FORCEPROP 0 LASTPIN (-3675 3650) $PN 23
J 0
(-3665 3660);
DISPLAY 0.680851 (-3665 3660);
PAINT MONO (-3665 3660);
FORCEPROP 0 LASTPIN (-3675 3700) $PN 22
J 0
(-3665 3710);
DISPLAY 0.680851 (-3665 3710);
PAINT MONO (-3665 3710);
FORCEPROP 0 LASTPIN (-3675 2600) $PN 116
J 0
(-3665 2610);
DISPLAY 0.680851 (-3665 2610);
PAINT MONO (-3665 2610);
FORCEPROP 0 LASTPIN (-3675 2650) $PN 115
J 0
(-3665 2660);
DISPLAY 0.680851 (-3665 2660);
PAINT MONO (-3665 2660);
FORCEPROP 0 LASTPIN (-3675 3750) $PN 34
J 0
(-3665 3760);
DISPLAY 0.680851 (-3665 3760);
PAINT MONO (-3665 3760);
FORCEPROP 0 LASTPIN (-3675 3800) $PN 33
J 0
(-3665 3810);
DISPLAY 0.680851 (-3665 3810);
PAINT MONO (-3665 3810);
FORCEPROP 0 LASTPIN (-3675 2700) $PN 127
J 0
(-3665 2710);
DISPLAY 0.680851 (-3665 2710);
PAINT MONO (-3665 2710);
FORCEPROP 0 LASTPIN (-3675 2750) $PN 126
J 0
(-3665 2760);
DISPLAY 0.680851 (-3665 2760);
PAINT MONO (-3665 2760);
FORCEPROP 0 LASTPIN (-3675 3850) $PN 45
J 0
(-3665 3860);
DISPLAY 0.680851 (-3665 3860);
PAINT MONO (-3665 3860);
FORCEPROP 0 LASTPIN (-3675 3900) $PN 44
J 0
(-3665 3910);
DISPLAY 0.680851 (-3665 3910);
PAINT MONO (-3665 3910);
FORCEPROP 0 LASTPIN (-3675 2800) $PN 138
J 0
(-3665 2810);
DISPLAY 0.680851 (-3665 2810);
PAINT MONO (-3665 2810);
FORCEPROP 0 LASTPIN (-3675 2850) $PN 137
J 0
(-3665 2860);
DISPLAY 0.680851 (-3665 2860);
PAINT MONO (-3665 2860);
FORCEPROP 0 LASTPIN (-3675 3950) $PN 56
J 0
(-3665 3960);
DISPLAY 0.680851 (-3665 3960);
PAINT MONO (-3665 3960);
FORCEPROP 0 LASTPIN (-3675 4000) $PN 55
J 0
(-3665 4010);
DISPLAY 0.680851 (-3665 4010);
PAINT MONO (-3665 4010);
FORCEPROP 0 LASTPIN (-3675 2900) $PN 238
J 0
(-3665 2910);
DISPLAY 0.680851 (-3665 2910);
PAINT MONO (-3665 2910);
FORCEPROP 0 LASTPIN (-3675 2950) $PN 239
J 0
(-3665 2960);
DISPLAY 0.680851 (-3665 2960);
PAINT MONO (-3665 2960);
FORCEPROP 0 LASTPIN (-3675 4050) $PN 156
J 0
(-3665 4060);
DISPLAY 0.680851 (-3665 4060);
PAINT MONO (-3665 4060);
FORCEPROP 0 LASTPIN (-3675 4100) $PN 157
J 0
(-3665 4110);
DISPLAY 0.680851 (-3665 4110);
PAINT MONO (-3665 4110);
FORCEPROP 0 LASTPIN (-3675 3000) $PN 249
J 0
(-3665 3010);
DISPLAY 0.680851 (-3665 3010);
PAINT MONO (-3665 3010);
FORCEPROP 0 LASTPIN (-3675 3050) $PN 250
J 0
(-3665 3060);
DISPLAY 0.680851 (-3665 3060);
PAINT MONO (-3665 3060);
FORCEPROP 0 LASTPIN (-3675 4150) $PN 167
J 0
(-3665 4160);
DISPLAY 0.680851 (-3665 4160);
PAINT MONO (-3665 4160);
FORCEPROP 0 LASTPIN (-3675 4200) $PN 168
J 0
(-3665 4210);
DISPLAY 0.680851 (-3665 4210);
PAINT MONO (-3665 4210);
FORCEPROP 0 LASTPIN (-3675 3100) $PN 260
J 0
(-3665 3110);
DISPLAY 0.680851 (-3665 3110);
PAINT MONO (-3665 3110);
FORCEPROP 0 LASTPIN (-3675 3150) $PN 261
J 0
(-3665 3160);
DISPLAY 0.680851 (-3665 3160);
PAINT MONO (-3665 3160);
FORCEPROP 0 LASTPIN (-3675 4250) $PN 178
J 0
(-3665 4260);
DISPLAY 0.680851 (-3665 4260);
PAINT MONO (-3665 4260);
FORCEPROP 0 LASTPIN (-3675 4300) $PN 179
J 0
(-3665 4310);
DISPLAY 0.680851 (-3665 4310);
PAINT MONO (-3665 4310);
FORCEPROP 0 LASTPIN (-3675 3200) $PN 271
J 0
(-3665 3210);
DISPLAY 0.680851 (-3665 3210);
PAINT MONO (-3665 3210);
FORCEPROP 0 LASTPIN (-3675 3250) $PN 272
J 0
(-3665 3260);
DISPLAY 0.680851 (-3665 3260);
PAINT MONO (-3665 3260);
FORCEPROP 0 LASTPIN (-3675 4350) $PN 189
J 0
(-3665 4360);
DISPLAY 0.680851 (-3665 4360);
PAINT MONO (-3665 4360);
FORCEPROP 0 LASTPIN (-3675 4400) $PN 190
J 0
(-3665 4410);
DISPLAY 0.680851 (-3665 4410);
PAINT MONO (-3665 4410);
FORCEPROP 0 LASTPIN (-3675 3300) $PN 282
J 0
(-3665 3310);
DISPLAY 0.680851 (-3665 3310);
PAINT MONO (-3665 3310);
FORCEPROP 0 LASTPIN (-3675 3350) $PN 283
J 0
(-3665 3360);
DISPLAY 0.680851 (-3665 3360);
PAINT MONO (-3665 3360);
FORCEPROP 0 LASTPIN (-3675 4450) $PN 200
J 0
(-3665 4460);
DISPLAY 0.680851 (-3665 4460);
PAINT MONO (-3665 4460);
FORCEPROP 0 LASTPIN (-3675 4500) $PN 201
J 0
(-3665 4510);
DISPLAY 0.680851 (-3665 4510);
PAINT MONO (-3665 4510);
FORCEPROP 0 LASTPIN (-3675 3400) $PN 94
J 0
(-3665 3410);
DISPLAY 0.680851 (-3665 3410);
PAINT MONO (-3665 3410);
FORCEPROP 0 LASTPIN (-3675 3450) $PN 93
J 0
(-3665 3460);
DISPLAY 0.680851 (-3665 3460);
PAINT MONO (-3665 3460);
FORCEPROP 1 LAST MATERIAL IO
J 0
(-5025 4675);
DISPLAY 0.468085 (-5025 4675);
PAINT SKYBLUE (-5025 4675);
FORCEPROP 2 LAST VALUE SCONN288_DDR506112002KQ
J 0
(-4875 4875);
DISPLAY 0.489362 (-4875 4875);
PAINT SKYBLUE (-4875 4875);
FORCEPROP 2 LAST PART_TYPE SMLF
J 0
(-4875 4925);
DISPLAY 1.021277 (-4875 4925);
FORCEPROP 1 LAST CDS_LMAN_SYM_OUTLINE -600,1150,600,-1150
J 0
(-4425 3500);
DISPLAY 0.468085 (-4425 3500);
PAINT GREEN (-4425 3500);
DISPLAY INVISIBLE (-4425 3500);
FORCEPROP 1 LAST NEEDS_NO_SIZE TRUE
J 0
(-4425 3500);
DISPLAY 0.723404 (-4425 3500);
PAINT GREEN (-4425 3500);
DISPLAY INVISIBLE (-4425 3500);
FORCEPROP 2 LAST CDS_LIB pure_quanta
J 0
(-4425 3500);
DISPLAY INVISIBLE (-4425 3500);
FORCEPROP 1 LAST PATH I235
J 0
(-4425 3500);
DISPLAY 0.723404 (-4425 3500);
PAINT GREEN (-4425 3500);
DISPLAY INVISIBLE (-4425 3500);
FORCEPROP 1 LAST PART_NUMBER DFHST8FS479
J 0
(-5025 4750);
DISPLAY 0.468085 (-5025 4750);
PAINT SKYBLUE (-5025 4750);
DISPLAY INVISIBLE (-5025 4750);
FORCEADD GND..1
(-2850 5475);
FORCEPROP 3 LASTPIN (-2850 5525) SIG_NAME GND\g
J 0
(-2840 5535);
DISPLAY 0.659574 (-2840 5535);
PAINT MONO (-2840 5535);
DISPLAY INVISIBLE (-2840 5535);
FORCEPROP 1 LAST SIZE 1B
J 0
(-2775 5425);
DISPLAY 0.723404 (-2775 5425);
PAINT GREEN (-2775 5425);
DISPLAY INVISIBLE (-2775 5425);
FORCEPROP 2 LAST BOM_COST MEM
J 0
(-2825 5600);
DISPLAY 0.659574 (-2825 5600);
DISPLAY INVISIBLE (-2825 5600);
FORCEPROP 2 LAST CDS_LIB pure_quanta_power
J 0
(-2850 5475);
DISPLAY INVISIBLE (-2850 5475);
FORCEPROP 2 LAST ROOM MEM_EFGH_DECOUPLING_CAPS
J 0
(-2825 5550);
DISPLAY 0.659574 (-2825 5550);
PAINT RED (-2825 5550);
DISPLAY INVISIBLE (-2825 5550);
FORCEPROP 1 LAST HDL_POWER GND
J 0
(-2850 5625);
DISPLAY 0.723404 (-2850 5625);
PAINT GREEN (-2850 5625);
DISPLAY INVISIBLE (-2850 5625);
FORCEPROP 1 LAST PATH I236
J 0
(-2775 5475);
DISPLAY 0.872340 (-2775 5475);
PAINT AQUA (-2775 5475);
DISPLAY INVISIBLE (-2775 5475);
FORCEADD Q_CAP..1
R 2
(-2850 5825);
FORCEPROP 1 LAST LOCATION C546
J 2
(-2900 5925);
DISPLAY 0.489362 (-2900 5925);
PAINT SKYBLUE (-2900 5925);
FORCEPROP 0 LAST $SEC 1
J 0
(-2900 5975);
DISPLAY 0.680851 (-2900 5975);
PAINT MONO (-2900 5975);
DISPLAY INVISIBLE (-2900 5975);
FORCEPROP 0 LAST CDS_SEC 1
J 0
(-2900 5975);
DISPLAY 0.680851 (-2900 5975);
DISPLAY INVISIBLE (-2900 5975);
FORCEPROP 1 LASTPIN (-2850 5925) $PN 1
J 2
(-2860 5905);
DISPLAY 0.489362 (-2860 5905);
PAINT MONO (-2860 5905);
FORCEPROP 1 LASTPIN (-2850 5725) $PN 2
J 2
(-2860 5705);
DISPLAY 0.489362 (-2860 5705);
PAINT MONO (-2860 5705);
FORCEPROP 1 LAST PACK_TYPE C0805
J 2
(-2900 5625);
DISPLAY 0.489362 (-2900 5625);
PAINT SKYBLUE (-2900 5625);
FORCEPROP 1 LAST VOLTAGE 25V
J 2
(-2900 5825);
DISPLAY 0.489362 (-2900 5825);
PAINT SKYBLUE (-2900 5825);
FORCEPROP 1 LAST VALUE 10UF
J 2
(-2900 5875);
DISPLAY 0.489362 (-2900 5875);
PAINT SKYBLUE (-2900 5875);
FORCEPROP 1 LAST TOLERANCE 10%
J 2
(-2900 5775);
DISPLAY 0.489362 (-2900 5775);
PAINT SKYBLUE (-2900 5775);
FORCEPROP 1 LAST MATERIAL X6S
J 2
(-2900 5725);
DISPLAY 0.489362 (-2900 5725);
PAINT SKYBLUE (-2900 5725);
FORCEPROP 0 LAST BOM_COST MEM
J 2
(-2905 5970);
DISPLAY 0.595745 (-2905 5970);
PAINT MONO (-2905 5970);
DISPLAY INVISIBLE (-2905 5970);
FORCEPROP 2 LAST CDS_LIB pure_quanta
J 0
(-2850 5825);
DISPLAY INVISIBLE (-2850 5825);
FORCEPROP 2 LAST ROOM 
J 2
(-2905 5970);
DISPLAY 0.595745 (-2905 5970);
PAINT RED (-2905 5970);
DISPLAY INVISIBLE (-2905 5970);
FORCEPROP 1 LAST PATH I237
J 2
(-2900 5975);
DISPLAY 0.978723 (-2900 5975);
PAINT WHITE (-2900 5975);
DISPLAY INVISIBLE (-2900 5975);
FORCEPROP 1 LAST PART_NUMBER CH6104KEA00
J 2
(-2900 5675);
DISPLAY 0.489362 (-2900 5675);
PAINT SKYBLUE (-2900 5675);
DISPLAY INVISIBLE (-2900 5675);
FORCEADD Q_CAP..1
R 2
(-2275 5825);
FORCEPROP 1 LAST LOCATION C547
J 2
(-2325 5925);
DISPLAY 0.489362 (-2325 5925);
PAINT SKYBLUE (-2325 5925);
FORCEPROP 0 LAST $SEC 1
J 0
(-2325 5975);
DISPLAY 0.680851 (-2325 5975);
PAINT MONO (-2325 5975);
DISPLAY INVISIBLE (-2325 5975);
FORCEPROP 0 LAST CDS_SEC 1
J 0
(-2325 5975);
DISPLAY 0.680851 (-2325 5975);
DISPLAY INVISIBLE (-2325 5975);
FORCEPROP 1 LASTPIN (-2275 5925) $PN 1
J 2
(-2285 5905);
DISPLAY 0.489362 (-2285 5905);
PAINT MONO (-2285 5905);
FORCEPROP 1 LASTPIN (-2275 5725) $PN 2
J 2
(-2285 5705);
DISPLAY 0.489362 (-2285 5705);
PAINT MONO (-2285 5705);
FORCEPROP 1 LAST PACK_TYPE C0805
J 2
(-2325 5625);
DISPLAY 0.489362 (-2325 5625);
PAINT SKYBLUE (-2325 5625);
FORCEPROP 1 LAST VOLTAGE 25V
J 2
(-2325 5825);
DISPLAY 0.489362 (-2325 5825);
PAINT SKYBLUE (-2325 5825);
FORCEPROP 1 LAST VALUE 10UF
J 2
(-2325 5875);
DISPLAY 0.489362 (-2325 5875);
PAINT SKYBLUE (-2325 5875);
FORCEPROP 1 LAST TOLERANCE 10%
J 2
(-2325 5775);
DISPLAY 0.489362 (-2325 5775);
PAINT SKYBLUE (-2325 5775);
FORCEPROP 1 LAST MATERIAL X6S
J 2
(-2325 5725);
DISPLAY 0.489362 (-2325 5725);
PAINT SKYBLUE (-2325 5725);
FORCEPROP 0 LAST BOM_COST MEM
J 2
(-2330 5970);
DISPLAY 0.595745 (-2330 5970);
PAINT MONO (-2330 5970);
DISPLAY INVISIBLE (-2330 5970);
FORCEPROP 2 LAST CDS_LIB pure_quanta
J 0
(-2275 5825);
DISPLAY INVISIBLE (-2275 5825);
FORCEPROP 2 LAST ROOM 
J 2
(-2330 5970);
DISPLAY 0.595745 (-2330 5970);
PAINT RED (-2330 5970);
DISPLAY INVISIBLE (-2330 5970);
FORCEPROP 1 LAST PATH I238
J 2
(-2325 5975);
DISPLAY 0.978723 (-2325 5975);
PAINT WHITE (-2325 5975);
DISPLAY INVISIBLE (-2325 5975);
FORCEPROP 1 LAST PART_NUMBER CH6104KEA00
J 2
(-2325 5675);
DISPLAY 0.489362 (-2325 5675);
PAINT SKYBLUE (-2325 5675);
DISPLAY INVISIBLE (-2325 5675);
FORCEADD UNIVERSAL_POWER..1
(-2850 6150);
FORCEPROP 3 LASTPIN (-2850 6100) SIG_NAME P12V_MEM_CPU1\g
J 0
(-2840 6110);
DISPLAY 0.659574 (-2840 6110);
PAINT MONO (-2840 6110);
DISPLAY INVISIBLE (-2840 6110);
FORCEPROP 1 LAST HDL_POWER P12V_MEM_CPU1
J 1
(-2850 6200);
DISPLAY 0.489362 (-2850 6200);
PAINT GREEN (-2850 6200);
FORCEPROP 2 LAST CDS_LIB pure_quanta_power
J 0
(-2850 6150);
DISPLAY INVISIBLE (-2850 6150);
FORCEPROP 1 LAST PATH I239
J 0
(-2800 6175);
DISPLAY 0.872340 (-2800 6175);
PAINT AQUA (-2800 6175);
DISPLAY INVISIBLE (-2800 6175);
FORCEADD TAP..1
R 2
(-7700 3175);
FORCEPROP 3 LASTPIN (-7650 3175) SIG_NAME M_K_CPU1_SB_CB<1>
J 0
(-7640 3185);
DISPLAY 0.659574 (-7640 3185);
PAINT MONO (-7640 3185);
DISPLAY INVISIBLE (-7640 3185);
FORCEPROP 1 LASTPIN (-7650 3175) BN 1
J 2
(-7638 3183);
DISPLAY 0.489362 (-7638 3183);
PAINT GREEN (-7638 3183);
FORCEPROP 2 LAST CDS_LIB mstr_standard
J 0
(-7700 3175);
DISPLAY 0.723404 (-7700 3175);
PAINT MONO (-7700 3175);
DISPLAY INVISIBLE (-7700 3175);
FORCEPROP 1 LAST BODY_TYPE PLUMBING
J 2
(-7700 3225);
DISPLAY 0.872340 (-7700 3225);
PAINT GREEN (-7700 3225);
DISPLAY INVISIBLE (-7700 3225);
FORCEPROP 1 LAST HDL_TAP TRUE
J 2
(-8025 3050);
DISPLAY 0.872340 (-8025 3050);
DISPLAY INVISIBLE (-8025 3050);
FORCEPROP 1 LAST PATH I24
J 2
(-7698 3175);
DISPLAY 0.872340 (-7698 3175);
PAINT GREEN (-7698 3175);
DISPLAY INVISIBLE (-7698 3175);
FORCEADD OFFPAGE..1
(-8350 2550);
FORCEPROP 2 LAST $XR5 109 
J 0
(-9202 2550);
DISPLAY 0.638298 (-9202 2550);
PAINT MONO (-9202 2550);
FORCEPROP 2 LAST $XR4 107 
J 0
(-9082 2550);
DISPLAY 0.638298 (-9082 2550);
PAINT MONO (-9082 2550);
FORCEPROP 2 LAST $XR3 106 
J 0
(-8962 2550);
DISPLAY 0.638298 (-8962 2550);
PAINT MONO (-8962 2550);
FORCEPROP 2 LAST $XR2 105 
J 0
(-8842 2550);
DISPLAY 0.638298 (-8842 2550);
PAINT MONO (-8842 2550);
FORCEPROP 2 LAST $XR1 104 
J 0
(-8722 2550);
DISPLAY 0.638298 (-8722 2550);
PAINT MONO (-8722 2550);
FORCEPROP 2 LAST $XR0 159 
J 0
(-8602 2550);
DISPLAY 0.638298 (-8602 2550);
PAINT MONO (-8602 2550);
FORCEPROP 2 LAST CDS_LIB mstr_standard
J 0
(-8350 2550);
DISPLAY 0.808511 (-8350 2550);
DISPLAY INVISIBLE (-8350 2550);
FORCEPROP 1 LAST OFFPAGE TRUE
J 0
(-8025 2425);
DISPLAY 0.872340 (-8025 2425);
PAINT GREEN (-8025 2425);
DISPLAY INVISIBLE (-8025 2425);
FORCEPROP 1 LAST COMMENT_BODY TRUE
J 0
(-8225 2450);
DISPLAY 0.872340 (-8225 2450);
PAINT GREEN (-8225 2450);
DISPLAY INVISIBLE (-8225 2450);
FORCEPROP 2 LAST PATH I240
J 0
(-8625 2600);
DISPLAY 0.680851 (-8625 2600);
DISPLAY INVISIBLE (-8625 2600);
FORCEADD Q_RES..1
(-7750 2550);
FORCEPROP 1 LAST LOCATION R1590
J 0
(-7800 2575);
DISPLAY 0.510638 (-7800 2575);
PAINT SKYBLUE (-7800 2575);
FORCEPROP 0 LAST $SEC 1
J 0
(-7800 2650);
DISPLAY 0.680851 (-7800 2650);
PAINT MONO (-7800 2650);
DISPLAY INVISIBLE (-7800 2650);
FORCEPROP 0 LAST CDS_SEC 1
J 0
(-7800 2650);
DISPLAY 0.680851 (-7800 2650);
DISPLAY INVISIBLE (-7800 2650);
FORCEPROP 1 LASTPIN (-7850 2550) $PN 1
J 0
(-7838 2562);
DISPLAY 0.787234 (-7838 2562);
PAINT MONO (-7838 2562);
FORCEPROP 1 LASTPIN (-7650 2550) $PN 2
J 0
(-7688 2562);
DISPLAY 0.787234 (-7688 2562);
PAINT MONO (-7688 2562);
FORCEPROP 1 LAST VALUE 49.9
J 2
(-7575 2600);
DISPLAY 0.510638 (-7575 2600);
PAINT SKYBLUE (-7575 2600);
FORCEPROP 2 LAST CDS_LIB pure_quanta
J 0
(-7750 2550);
DISPLAY INVISIBLE (-7750 2550);
FORCEPROP 1 LAST TOLERANCE 1%
J 0
(-7750 2450);
DISPLAY 0.978723 (-7750 2450);
DISPLAY INVISIBLE (-7750 2450);
FORCEPROP 1 LAST WATTAGE 1/16W
J 2
(-7775 2400);
DISPLAY 0.978723 (-7775 2400);
DISPLAY INVISIBLE (-7775 2400);
FORCEPROP 1 LAST PACK_TYPE 0402LF
J 0
(-7500 2400);
DISPLAY 0.978723 (-7500 2400);
DISPLAY INVISIBLE (-7500 2400);
FORCEPROP 1 LAST MATERIAL CHIP
J 0
(-7750 2400);
DISPLAY 0.978723 (-7750 2400);
DISPLAY INVISIBLE (-7750 2400);
FORCEPROP 1 LAST PATH I241
J 0
(-7800 2700);
DISPLAY 0.978723 (-7800 2700);
PAINT WHITE (-7800 2700);
DISPLAY INVISIBLE (-7800 2700);
FORCEPROP 1 LAST PART_NUMBER CS04992FB07
J 0
(-7800 2650);
DISPLAY 0.978723 (-7800 2650);
DISPLAY INVISIBLE (-7800 2650);
FORCEADD Q_RES..1
(-8125 2775);
FORCEPROP 1 LAST LOCATION R1710
J 0
(-8300 2775);
DISPLAY 0.510638 (-8300 2775);
FORCEPROP 0 LAST $SEC 1
J 0
(-8275 2825);
DISPLAY 0.680851 (-8275 2825);
PAINT MONO (-8275 2825);
DISPLAY INVISIBLE (-8275 2825);
FORCEPROP 0 LAST CDS_SEC 1
J 0
(-8275 2825);
DISPLAY 0.680851 (-8275 2825);
DISPLAY INVISIBLE (-8275 2825);
FORCEPROP 1 LASTPIN (-8225 2775) $PN 1
J 0
(-8213 2787);
DISPLAY 0.787234 (-8213 2787);
PAINT MONO (-8213 2787);
FORCEPROP 1 LASTPIN (-8025 2775) $PN 2
J 0
(-8063 2787);
DISPLAY 0.787234 (-8063 2787);
PAINT MONO (-8063 2787);
FORCEPROP 1 LAST VALUE 10
J 2
(-7975 2775);
DISPLAY 0.404255 (-7975 2775);
FORCEPROP 1 LAST PACK_TYPE 0402LF
J 0
(-8075 2750);
DISPLAY 0.404255 (-8075 2750);
FORCEPROP 1 LAST MATERIAL CHIP
J 0
(-8225 2750);
DISPLAY 0.404255 (-8225 2750);
FORCEPROP 2 LAST CDS_LIB pure_quanta
J 0
(-8125 2775);
DISPLAY INVISIBLE (-8125 2775);
FORCEPROP 1 LAST WATTAGE 1/16W
J 2
(-8150 2625);
DISPLAY 0.978723 (-8150 2625);
DISPLAY INVISIBLE (-8150 2625);
FORCEPROP 1 LAST TOLERANCE 1%
J 0
(-8125 2675);
DISPLAY 0.978723 (-8125 2675);
DISPLAY INVISIBLE (-8125 2675);
FORCEPROP 1 LAST PATH I242
J 0
(-8175 2925);
DISPLAY 0.978723 (-8175 2925);
PAINT WHITE (-8175 2925);
DISPLAY INVISIBLE (-8175 2925);
FORCEPROP 1 LAST PART_NUMBER CS01002FB07
J 0
(-8175 2875);
DISPLAY 0.978723 (-8175 2875);
DISPLAY INVISIBLE (-8175 2875);
FORCEADD OFFPAGE..6
(-8800 2650);
FORCEPROP 2 LAST $XR5 159 
J 0
(-9320 2614);
DISPLAY 0.638298 (-9320 2614);
PAINT MONO (-9320 2614);
FORCEPROP 2 LAST $XR4 109 
J 0
(-9200 2614);
DISPLAY 0.638298 (-9200 2614);
PAINT MONO (-9200 2614);
FORCEPROP 2 LAST $XR3 107 
J 0
(-9080 2614);
DISPLAY 0.638298 (-9080 2614);
PAINT MONO (-9080 2614);
FORCEPROP 2 LAST $XR2 106 
J 0
(-9320 2650);
DISPLAY 0.638298 (-9320 2650);
PAINT MONO (-9320 2650);
FORCEPROP 2 LAST $XR1 105 
J 0
(-9200 2650);
DISPLAY 0.638298 (-9200 2650);
PAINT MONO (-9200 2650);
FORCEPROP 2 LAST $XR0 104 
J 0
(-9080 2650);
DISPLAY 0.638298 (-9080 2650);
PAINT MONO (-9080 2650);
FORCEPROP 2 LAST CDS_LIB mstr_standard
J 0
(-8800 2650);
DISPLAY 0.808511 (-8800 2650);
DISPLAY INVISIBLE (-8800 2650);
FORCEPROP 1 LAST OFFPAGE TRUE
J 0
(-8475 2525);
DISPLAY 0.872340 (-8475 2525);
PAINT GREEN (-8475 2525);
DISPLAY INVISIBLE (-8475 2525);
FORCEPROP 1 LAST COMMENT_BODY TRUE
J 0
(-8700 2575);
DISPLAY 0.872340 (-8700 2575);
PAINT GREEN (-8700 2575);
DISPLAY INVISIBLE (-8700 2575);
FORCEPROP 2 LAST PATH I243
J 0
(-9075 2700);
DISPLAY 0.680851 (-9075 2700);
DISPLAY INVISIBLE (-9075 2700);
FORCEADD TAP..1
R 2
(-7700 3225);
FORCEPROP 3 LASTPIN (-7650 3225) SIG_NAME M_K_CPU1_SB_CB<2>
J 0
(-7640 3235);
DISPLAY 0.659574 (-7640 3235);
PAINT MONO (-7640 3235);
DISPLAY INVISIBLE (-7640 3235);
FORCEPROP 1 LASTPIN (-7650 3225) BN 2
J 2
(-7638 3233);
DISPLAY 0.489362 (-7638 3233);
PAINT GREEN (-7638 3233);
FORCEPROP 2 LAST CDS_LIB mstr_standard
J 0
(-7700 3225);
DISPLAY 0.723404 (-7700 3225);
PAINT MONO (-7700 3225);
DISPLAY INVISIBLE (-7700 3225);
FORCEPROP 1 LAST BODY_TYPE PLUMBING
J 2
(-7700 3275);
DISPLAY 0.872340 (-7700 3275);
PAINT GREEN (-7700 3275);
DISPLAY INVISIBLE (-7700 3275);
FORCEPROP 1 LAST HDL_TAP TRUE
J 2
(-8025 3100);
DISPLAY 0.872340 (-8025 3100);
DISPLAY INVISIBLE (-8025 3100);
FORCEPROP 1 LAST PATH I25
J 2
(-7698 3225);
DISPLAY 0.872340 (-7698 3225);
PAINT GREEN (-7698 3225);
DISPLAY INVISIBLE (-7698 3225);
FORCEADD TAP..1
R 2
(-7700 3325);
FORCEPROP 3 LASTPIN (-7650 3325) SIG_NAME M_K_CPU1_SB_CB<4>
J 0
(-7640 3335);
DISPLAY 0.659574 (-7640 3335);
PAINT MONO (-7640 3335);
DISPLAY INVISIBLE (-7640 3335);
FORCEPROP 1 LASTPIN (-7650 3325) BN 4
J 2
(-7638 3333);
DISPLAY 0.489362 (-7638 3333);
PAINT GREEN (-7638 3333);
FORCEPROP 2 LAST CDS_LIB mstr_standard
J 0
(-7700 3325);
DISPLAY 0.723404 (-7700 3325);
PAINT MONO (-7700 3325);
DISPLAY INVISIBLE (-7700 3325);
FORCEPROP 1 LAST BODY_TYPE PLUMBING
J 2
(-7700 3375);
DISPLAY 0.872340 (-7700 3375);
PAINT GREEN (-7700 3375);
DISPLAY INVISIBLE (-7700 3375);
FORCEPROP 1 LAST HDL_TAP TRUE
J 2
(-8025 3200);
DISPLAY 0.872340 (-8025 3200);
DISPLAY INVISIBLE (-8025 3200);
FORCEPROP 1 LAST PATH I26
J 2
(-7698 3325);
DISPLAY 0.872340 (-7698 3325);
PAINT GREEN (-7698 3325);
DISPLAY INVISIBLE (-7698 3325);
FORCEADD TAP..1
R 2
(-7700 3375);
FORCEPROP 3 LASTPIN (-7650 3375) SIG_NAME M_K_CPU1_SB_CB<5>
J 0
(-7640 3385);
DISPLAY 0.659574 (-7640 3385);
PAINT MONO (-7640 3385);
DISPLAY INVISIBLE (-7640 3385);
FORCEPROP 1 LASTPIN (-7650 3375) BN 5
J 2
(-7638 3383);
DISPLAY 0.489362 (-7638 3383);
PAINT GREEN (-7638 3383);
FORCEPROP 2 LAST CDS_LIB mstr_standard
J 0
(-7700 3375);
DISPLAY 0.723404 (-7700 3375);
PAINT MONO (-7700 3375);
DISPLAY INVISIBLE (-7700 3375);
FORCEPROP 1 LAST BODY_TYPE PLUMBING
J 2
(-7700 3425);
DISPLAY 0.872340 (-7700 3425);
PAINT GREEN (-7700 3425);
DISPLAY INVISIBLE (-7700 3425);
FORCEPROP 1 LAST HDL_TAP TRUE
J 2
(-8025 3250);
DISPLAY 0.872340 (-8025 3250);
DISPLAY INVISIBLE (-8025 3250);
FORCEPROP 1 LAST PATH I27
J 2
(-7698 3375);
DISPLAY 0.872340 (-7698 3375);
PAINT GREEN (-7698 3375);
DISPLAY INVISIBLE (-7698 3375);
FORCEADD TAP..1
R 2
(-7700 3275);
FORCEPROP 3 LASTPIN (-7650 3275) SIG_NAME M_K_CPU1_SB_CB<3>
J 0
(-7640 3285);
DISPLAY 0.659574 (-7640 3285);
PAINT MONO (-7640 3285);
DISPLAY INVISIBLE (-7640 3285);
FORCEPROP 1 LASTPIN (-7650 3275) BN 3
J 2
(-7638 3283);
DISPLAY 0.489362 (-7638 3283);
PAINT GREEN (-7638 3283);
FORCEPROP 2 LAST CDS_LIB mstr_standard
J 0
(-7700 3275);
DISPLAY 0.723404 (-7700 3275);
PAINT MONO (-7700 3275);
DISPLAY INVISIBLE (-7700 3275);
FORCEPROP 1 LAST BODY_TYPE PLUMBING
J 2
(-7700 3325);
DISPLAY 0.872340 (-7700 3325);
PAINT GREEN (-7700 3325);
DISPLAY INVISIBLE (-7700 3325);
FORCEPROP 1 LAST HDL_TAP TRUE
J 2
(-8025 3150);
DISPLAY 0.872340 (-8025 3150);
DISPLAY INVISIBLE (-8025 3150);
FORCEPROP 1 LAST PATH I28
J 2
(-7698 3275);
DISPLAY 0.872340 (-7698 3275);
PAINT GREEN (-7698 3275);
DISPLAY INVISIBLE (-7698 3275);
FORCEADD TAP..1
R 2
(-7700 3575);
FORCEPROP 3 LASTPIN (-7650 3575) SIG_NAME M_K_CPU1_SA_CB<0>
J 0
(-7640 3585);
DISPLAY 0.659574 (-7640 3585);
PAINT MONO (-7640 3585);
DISPLAY INVISIBLE (-7640 3585);
FORCEPROP 1 LASTPIN (-7650 3575) BN 0
J 2
(-7638 3583);
DISPLAY 0.489362 (-7638 3583);
PAINT GREEN (-7638 3583);
FORCEPROP 2 LAST CDS_LIB mstr_standard
J 0
(-7700 3575);
DISPLAY 0.723404 (-7700 3575);
PAINT MONO (-7700 3575);
DISPLAY INVISIBLE (-7700 3575);
FORCEPROP 1 LAST BODY_TYPE PLUMBING
J 2
(-7700 3625);
DISPLAY 0.872340 (-7700 3625);
PAINT GREEN (-7700 3625);
DISPLAY INVISIBLE (-7700 3625);
FORCEPROP 1 LAST HDL_TAP TRUE
J 2
(-8025 3450);
DISPLAY 0.872340 (-8025 3450);
DISPLAY INVISIBLE (-8025 3450);
FORCEPROP 1 LAST PATH I29
J 2
(-7698 3575);
DISPLAY 0.872340 (-7698 3575);
PAINT GREEN (-7698 3575);
DISPLAY INVISIBLE (-7698 3575);
FORCEADD TAP..1
R 2
(-7700 3625);
FORCEPROP 3 LASTPIN (-7650 3625) SIG_NAME M_K_CPU1_SA_CB<1>
J 0
(-7640 3635);
DISPLAY 0.659574 (-7640 3635);
PAINT MONO (-7640 3635);
DISPLAY INVISIBLE (-7640 3635);
FORCEPROP 1 LASTPIN (-7650 3625) BN 1
J 2
(-7638 3633);
DISPLAY 0.489362 (-7638 3633);
PAINT GREEN (-7638 3633);
FORCEPROP 2 LAST CDS_LIB mstr_standard
J 0
(-7700 3625);
DISPLAY 0.723404 (-7700 3625);
PAINT MONO (-7700 3625);
DISPLAY INVISIBLE (-7700 3625);
FORCEPROP 1 LAST BODY_TYPE PLUMBING
J 2
(-7700 3675);
DISPLAY 0.872340 (-7700 3675);
PAINT GREEN (-7700 3675);
DISPLAY INVISIBLE (-7700 3675);
FORCEPROP 1 LAST HDL_TAP TRUE
J 2
(-8025 3500);
DISPLAY 0.872340 (-8025 3500);
DISPLAY INVISIBLE (-8025 3500);
FORCEPROP 1 LAST PATH I30
J 2
(-7698 3625);
DISPLAY 0.872340 (-7698 3625);
PAINT GREEN (-7698 3625);
DISPLAY INVISIBLE (-7698 3625);
FORCEADD TAP..1
R 2
(-7700 3425);
FORCEPROP 3 LASTPIN (-7650 3425) SIG_NAME M_K_CPU1_SB_CB<6>
J 0
(-7640 3435);
DISPLAY 0.659574 (-7640 3435);
PAINT MONO (-7640 3435);
DISPLAY INVISIBLE (-7640 3435);
FORCEPROP 1 LASTPIN (-7650 3425) BN 6
J 2
(-7638 3433);
DISPLAY 0.489362 (-7638 3433);
PAINT GREEN (-7638 3433);
FORCEPROP 2 LAST CDS_LIB mstr_standard
J 0
(-7700 3425);
DISPLAY 0.723404 (-7700 3425);
PAINT MONO (-7700 3425);
DISPLAY INVISIBLE (-7700 3425);
FORCEPROP 1 LAST BODY_TYPE PLUMBING
J 2
(-7700 3475);
DISPLAY 0.872340 (-7700 3475);
PAINT GREEN (-7700 3475);
DISPLAY INVISIBLE (-7700 3475);
FORCEPROP 1 LAST HDL_TAP TRUE
J 2
(-8025 3300);
DISPLAY 0.872340 (-8025 3300);
DISPLAY INVISIBLE (-8025 3300);
FORCEPROP 1 LAST PATH I31
J 2
(-7698 3425);
DISPLAY 0.872340 (-7698 3425);
PAINT GREEN (-7698 3425);
DISPLAY INVISIBLE (-7698 3425);
FORCEADD TAP..1
R 2
(-7700 3475);
FORCEPROP 3 LASTPIN (-7650 3475) SIG_NAME M_K_CPU1_SB_CB<7>
J 0
(-7640 3485);
DISPLAY 0.659574 (-7640 3485);
PAINT MONO (-7640 3485);
DISPLAY INVISIBLE (-7640 3485);
FORCEPROP 1 LASTPIN (-7650 3475) BN 7
J 2
(-7638 3483);
DISPLAY 0.489362 (-7638 3483);
PAINT GREEN (-7638 3483);
FORCEPROP 2 LAST CDS_LIB mstr_standard
J 0
(-7700 3475);
DISPLAY 0.723404 (-7700 3475);
PAINT MONO (-7700 3475);
DISPLAY INVISIBLE (-7700 3475);
FORCEPROP 1 LAST BODY_TYPE PLUMBING
J 2
(-7700 3525);
DISPLAY 0.872340 (-7700 3525);
PAINT GREEN (-7700 3525);
DISPLAY INVISIBLE (-7700 3525);
FORCEPROP 1 LAST HDL_TAP TRUE
J 2
(-8025 3350);
DISPLAY 0.872340 (-8025 3350);
DISPLAY INVISIBLE (-8025 3350);
FORCEPROP 1 LAST PATH I32
J 2
(-7698 3475);
DISPLAY 0.872340 (-7698 3475);
PAINT GREEN (-7698 3475);
DISPLAY INVISIBLE (-7698 3475);
FORCEADD TAP..1
(-6000 2125);
FORCEPROP 3 LASTPIN (-6050 2125) SIG_NAME M_K_CPU1_SB_DQ<0>
J 0
(-6040 2135);
DISPLAY 0.659574 (-6040 2135);
PAINT MONO (-6040 2135);
DISPLAY INVISIBLE (-6040 2135);
FORCEPROP 1 LASTPIN (-6050 2125) BN 0
J 0
(-6062 2133);
DISPLAY 0.489362 (-6062 2133);
PAINT GREEN (-6062 2133);
FORCEPROP 2 LAST CDS_LIB mstr_standard
J 0
(-6000 2125);
DISPLAY 0.723404 (-6000 2125);
PAINT MONO (-6000 2125);
DISPLAY INVISIBLE (-6000 2125);
FORCEPROP 1 LAST BODY_TYPE PLUMBING
J 0
(-6000 2175);
DISPLAY 0.872340 (-6000 2175);
PAINT GREEN (-6000 2175);
DISPLAY INVISIBLE (-6000 2175);
FORCEPROP 1 LAST HDL_TAP TRUE
J 0
(-5675 2000);
DISPLAY 0.872340 (-5675 2000);
DISPLAY INVISIBLE (-5675 2000);
FORCEPROP 1 LAST PATH I33
J 0
(-6002 2125);
DISPLAY 0.872340 (-6002 2125);
PAINT GREEN (-6002 2125);
DISPLAY INVISIBLE (-6002 2125);
FORCEADD TAP..1
(-6000 2175);
FORCEPROP 3 LASTPIN (-6050 2175) SIG_NAME M_K_CPU1_SB_DQ<1>
J 0
(-6040 2185);
DISPLAY 0.659574 (-6040 2185);
PAINT MONO (-6040 2185);
DISPLAY INVISIBLE (-6040 2185);
FORCEPROP 1 LASTPIN (-6050 2175) BN 1
J 0
(-6062 2183);
DISPLAY 0.489362 (-6062 2183);
PAINT GREEN (-6062 2183);
FORCEPROP 2 LAST CDS_LIB mstr_standard
J 0
(-6000 2175);
DISPLAY 0.723404 (-6000 2175);
PAINT MONO (-6000 2175);
DISPLAY INVISIBLE (-6000 2175);
FORCEPROP 1 LAST BODY_TYPE PLUMBING
J 0
(-6000 2225);
DISPLAY 0.872340 (-6000 2225);
PAINT GREEN (-6000 2225);
DISPLAY INVISIBLE (-6000 2225);
FORCEPROP 1 LAST HDL_TAP TRUE
J 0
(-5675 2050);
DISPLAY 0.872340 (-5675 2050);
DISPLAY INVISIBLE (-5675 2050);
FORCEPROP 1 LAST PATH I34
J 0
(-6002 2175);
DISPLAY 0.872340 (-6002 2175);
PAINT GREEN (-6002 2175);
DISPLAY INVISIBLE (-6002 2175);
FORCEADD TAP..1
(-6000 2225);
FORCEPROP 3 LASTPIN (-6050 2225) SIG_NAME M_K_CPU1_SB_DQ<2>
J 0
(-6040 2235);
DISPLAY 0.659574 (-6040 2235);
PAINT MONO (-6040 2235);
DISPLAY INVISIBLE (-6040 2235);
FORCEPROP 1 LASTPIN (-6050 2225) BN 2
J 0
(-6062 2233);
DISPLAY 0.489362 (-6062 2233);
PAINT GREEN (-6062 2233);
FORCEPROP 2 LAST CDS_LIB mstr_standard
J 0
(-6000 2225);
DISPLAY 0.723404 (-6000 2225);
PAINT MONO (-6000 2225);
DISPLAY INVISIBLE (-6000 2225);
FORCEPROP 1 LAST BODY_TYPE PLUMBING
J 0
(-6000 2275);
DISPLAY 0.872340 (-6000 2275);
PAINT GREEN (-6000 2275);
DISPLAY INVISIBLE (-6000 2275);
FORCEPROP 1 LAST HDL_TAP TRUE
J 0
(-5675 2100);
DISPLAY 0.872340 (-5675 2100);
DISPLAY INVISIBLE (-5675 2100);
FORCEPROP 1 LAST PATH I35
J 0
(-6002 2225);
DISPLAY 0.872340 (-6002 2225);
PAINT GREEN (-6002 2225);
DISPLAY INVISIBLE (-6002 2225);
FORCEADD TAP..1
(-6000 2275);
FORCEPROP 3 LASTPIN (-6050 2275) SIG_NAME M_K_CPU1_SB_DQ<3>
J 0
(-6040 2285);
DISPLAY 0.659574 (-6040 2285);
PAINT MONO (-6040 2285);
DISPLAY INVISIBLE (-6040 2285);
FORCEPROP 1 LASTPIN (-6050 2275) BN 3
J 0
(-6062 2283);
DISPLAY 0.489362 (-6062 2283);
PAINT GREEN (-6062 2283);
FORCEPROP 2 LAST CDS_LIB mstr_standard
J 0
(-6000 2275);
DISPLAY 0.723404 (-6000 2275);
PAINT MONO (-6000 2275);
DISPLAY INVISIBLE (-6000 2275);
FORCEPROP 1 LAST BODY_TYPE PLUMBING
J 0
(-6000 2325);
DISPLAY 0.872340 (-6000 2325);
PAINT GREEN (-6000 2325);
DISPLAY INVISIBLE (-6000 2325);
FORCEPROP 1 LAST HDL_TAP TRUE
J 0
(-5675 2150);
DISPLAY 0.872340 (-5675 2150);
DISPLAY INVISIBLE (-5675 2150);
FORCEPROP 1 LAST PATH I36
J 0
(-6002 2275);
DISPLAY 0.872340 (-6002 2275);
PAINT GREEN (-6002 2275);
DISPLAY INVISIBLE (-6002 2275);
FORCEADD TAP..1
(-6000 2325);
FORCEPROP 3 LASTPIN (-6050 2325) SIG_NAME M_K_CPU1_SB_DQ<4>
J 0
(-6040 2335);
DISPLAY 0.659574 (-6040 2335);
PAINT MONO (-6040 2335);
DISPLAY INVISIBLE (-6040 2335);
FORCEPROP 1 LASTPIN (-6050 2325) BN 4
J 0
(-6062 2333);
DISPLAY 0.489362 (-6062 2333);
PAINT GREEN (-6062 2333);
FORCEPROP 2 LAST CDS_LIB mstr_standard
J 0
(-6000 2325);
DISPLAY 0.723404 (-6000 2325);
PAINT MONO (-6000 2325);
DISPLAY INVISIBLE (-6000 2325);
FORCEPROP 1 LAST BODY_TYPE PLUMBING
J 0
(-6000 2375);
DISPLAY 0.872340 (-6000 2375);
PAINT GREEN (-6000 2375);
DISPLAY INVISIBLE (-6000 2375);
FORCEPROP 1 LAST HDL_TAP TRUE
J 0
(-5675 2200);
DISPLAY 0.872340 (-5675 2200);
DISPLAY INVISIBLE (-5675 2200);
FORCEPROP 1 LAST PATH I37
J 0
(-6002 2325);
DISPLAY 0.872340 (-6002 2325);
PAINT GREEN (-6002 2325);
DISPLAY INVISIBLE (-6002 2325);
FORCEADD TAP..1
(-6000 2375);
FORCEPROP 3 LASTPIN (-6050 2375) SIG_NAME M_K_CPU1_SB_DQ<5>
J 0
(-6040 2385);
DISPLAY 0.659574 (-6040 2385);
PAINT MONO (-6040 2385);
DISPLAY INVISIBLE (-6040 2385);
FORCEPROP 1 LASTPIN (-6050 2375) BN 5
J 0
(-6062 2383);
DISPLAY 0.489362 (-6062 2383);
PAINT GREEN (-6062 2383);
FORCEPROP 2 LAST CDS_LIB mstr_standard
J 0
(-6000 2375);
DISPLAY 0.723404 (-6000 2375);
PAINT MONO (-6000 2375);
DISPLAY INVISIBLE (-6000 2375);
FORCEPROP 1 LAST BODY_TYPE PLUMBING
J 0
(-6000 2425);
DISPLAY 0.872340 (-6000 2425);
PAINT GREEN (-6000 2425);
DISPLAY INVISIBLE (-6000 2425);
FORCEPROP 1 LAST HDL_TAP TRUE
J 0
(-5675 2250);
DISPLAY 0.872340 (-5675 2250);
DISPLAY INVISIBLE (-5675 2250);
FORCEPROP 1 LAST PATH I38
J 0
(-6002 2375);
DISPLAY 0.872340 (-6002 2375);
PAINT GREEN (-6002 2375);
DISPLAY INVISIBLE (-6002 2375);
FORCEADD TAP..1
(-6000 2425);
FORCEPROP 3 LASTPIN (-6050 2425) SIG_NAME M_K_CPU1_SB_DQ<6>
J 0
(-6040 2435);
DISPLAY 0.659574 (-6040 2435);
PAINT MONO (-6040 2435);
DISPLAY INVISIBLE (-6040 2435);
FORCEPROP 1 LASTPIN (-6050 2425) BN 6
J 0
(-6062 2433);
DISPLAY 0.489362 (-6062 2433);
PAINT GREEN (-6062 2433);
FORCEPROP 2 LAST CDS_LIB mstr_standard
J 0
(-6000 2425);
DISPLAY 0.723404 (-6000 2425);
PAINT MONO (-6000 2425);
DISPLAY INVISIBLE (-6000 2425);
FORCEPROP 1 LAST BODY_TYPE PLUMBING
J 0
(-6000 2475);
DISPLAY 0.872340 (-6000 2475);
PAINT GREEN (-6000 2475);
DISPLAY INVISIBLE (-6000 2475);
FORCEPROP 1 LAST HDL_TAP TRUE
J 0
(-5675 2300);
DISPLAY 0.872340 (-5675 2300);
DISPLAY INVISIBLE (-5675 2300);
FORCEPROP 1 LAST PATH I39
J 0
(-6002 2425);
DISPLAY 0.872340 (-6002 2425);
PAINT GREEN (-6002 2425);
DISPLAY INVISIBLE (-6002 2425);
FORCEADD TAP..1
(-6000 2475);
FORCEPROP 3 LASTPIN (-6050 2475) SIG_NAME M_K_CPU1_SB_DQ<7>
J 0
(-6040 2485);
DISPLAY 0.659574 (-6040 2485);
PAINT MONO (-6040 2485);
DISPLAY INVISIBLE (-6040 2485);
FORCEPROP 1 LASTPIN (-6050 2475) BN 7
J 0
(-6062 2483);
DISPLAY 0.489362 (-6062 2483);
PAINT GREEN (-6062 2483);
FORCEPROP 2 LAST CDS_LIB mstr_standard
J 0
(-6000 2475);
DISPLAY 0.723404 (-6000 2475);
PAINT MONO (-6000 2475);
DISPLAY INVISIBLE (-6000 2475);
FORCEPROP 1 LAST BODY_TYPE PLUMBING
J 0
(-6000 2525);
DISPLAY 0.872340 (-6000 2525);
PAINT GREEN (-6000 2525);
DISPLAY INVISIBLE (-6000 2525);
FORCEPROP 1 LAST HDL_TAP TRUE
J 0
(-5675 2350);
DISPLAY 0.872340 (-5675 2350);
DISPLAY INVISIBLE (-5675 2350);
FORCEPROP 1 LAST PATH I40
J 0
(-6002 2475);
DISPLAY 0.872340 (-6002 2475);
PAINT GREEN (-6002 2475);
DISPLAY INVISIBLE (-6002 2475);
FORCEADD TAP..1
(-6000 2525);
FORCEPROP 3 LASTPIN (-6050 2525) SIG_NAME M_K_CPU1_SB_DQ<8>
J 0
(-6040 2535);
DISPLAY 0.659574 (-6040 2535);
PAINT MONO (-6040 2535);
DISPLAY INVISIBLE (-6040 2535);
FORCEPROP 1 LASTPIN (-6050 2525) BN 8
J 0
(-6062 2533);
DISPLAY 0.489362 (-6062 2533);
PAINT GREEN (-6062 2533);
FORCEPROP 2 LAST CDS_LIB mstr_standard
J 0
(-6000 2525);
DISPLAY 0.723404 (-6000 2525);
PAINT MONO (-6000 2525);
DISPLAY INVISIBLE (-6000 2525);
FORCEPROP 1 LAST BODY_TYPE PLUMBING
J 0
(-6000 2575);
DISPLAY 0.872340 (-6000 2575);
PAINT GREEN (-6000 2575);
DISPLAY INVISIBLE (-6000 2575);
FORCEPROP 1 LAST HDL_TAP TRUE
J 0
(-5675 2400);
DISPLAY 0.872340 (-5675 2400);
DISPLAY INVISIBLE (-5675 2400);
FORCEPROP 1 LAST PATH I41
J 0
(-6002 2525);
DISPLAY 0.872340 (-6002 2525);
PAINT GREEN (-6002 2525);
DISPLAY INVISIBLE (-6002 2525);
FORCEADD TAP..1
(-6000 2625);
FORCEPROP 3 LASTPIN (-6050 2625) SIG_NAME M_K_CPU1_SB_DQ<10>
J 0
(-6040 2635);
DISPLAY 0.659574 (-6040 2635);
PAINT MONO (-6040 2635);
DISPLAY INVISIBLE (-6040 2635);
FORCEPROP 1 LASTPIN (-6050 2625) BN 10
J 0
(-6062 2633);
DISPLAY 0.489362 (-6062 2633);
PAINT GREEN (-6062 2633);
FORCEPROP 2 LAST CDS_LIB mstr_standard
J 0
(-6000 2625);
DISPLAY 0.723404 (-6000 2625);
PAINT MONO (-6000 2625);
DISPLAY INVISIBLE (-6000 2625);
FORCEPROP 1 LAST BODY_TYPE PLUMBING
J 0
(-6000 2675);
DISPLAY 0.872340 (-6000 2675);
PAINT GREEN (-6000 2675);
DISPLAY INVISIBLE (-6000 2675);
FORCEPROP 1 LAST HDL_TAP TRUE
J 0
(-5675 2500);
DISPLAY 0.872340 (-5675 2500);
DISPLAY INVISIBLE (-5675 2500);
FORCEPROP 1 LAST PATH I42
J 0
(-6002 2625);
DISPLAY 0.872340 (-6002 2625);
PAINT GREEN (-6002 2625);
DISPLAY INVISIBLE (-6002 2625);
FORCEADD TAP..1
(-6000 2575);
FORCEPROP 3 LASTPIN (-6050 2575) SIG_NAME M_K_CPU1_SB_DQ<9>
J 0
(-6040 2585);
DISPLAY 0.659574 (-6040 2585);
PAINT MONO (-6040 2585);
DISPLAY INVISIBLE (-6040 2585);
FORCEPROP 1 LASTPIN (-6050 2575) BN 9
J 0
(-6062 2583);
DISPLAY 0.489362 (-6062 2583);
PAINT GREEN (-6062 2583);
FORCEPROP 2 LAST CDS_LIB mstr_standard
J 0
(-6000 2575);
DISPLAY 0.723404 (-6000 2575);
PAINT MONO (-6000 2575);
DISPLAY INVISIBLE (-6000 2575);
FORCEPROP 1 LAST BODY_TYPE PLUMBING
J 0
(-6000 2625);
DISPLAY 0.872340 (-6000 2625);
PAINT GREEN (-6000 2625);
DISPLAY INVISIBLE (-6000 2625);
FORCEPROP 1 LAST HDL_TAP TRUE
J 0
(-5675 2450);
DISPLAY 0.872340 (-5675 2450);
DISPLAY INVISIBLE (-5675 2450);
FORCEPROP 1 LAST PATH I43
J 0
(-6002 2575);
DISPLAY 0.872340 (-6002 2575);
PAINT GREEN (-6002 2575);
DISPLAY INVISIBLE (-6002 2575);
FORCEADD TAP..1
(-6000 2675);
FORCEPROP 3 LASTPIN (-6050 2675) SIG_NAME M_K_CPU1_SB_DQ<11>
J 0
(-6040 2685);
DISPLAY 0.659574 (-6040 2685);
PAINT MONO (-6040 2685);
DISPLAY INVISIBLE (-6040 2685);
FORCEPROP 1 LASTPIN (-6050 2675) BN 11
J 0
(-6062 2683);
DISPLAY 0.489362 (-6062 2683);
PAINT GREEN (-6062 2683);
FORCEPROP 2 LAST CDS_LIB mstr_standard
J 0
(-6000 2675);
DISPLAY 0.723404 (-6000 2675);
PAINT MONO (-6000 2675);
DISPLAY INVISIBLE (-6000 2675);
FORCEPROP 1 LAST BODY_TYPE PLUMBING
J 0
(-6000 2725);
DISPLAY 0.872340 (-6000 2725);
PAINT GREEN (-6000 2725);
DISPLAY INVISIBLE (-6000 2725);
FORCEPROP 1 LAST HDL_TAP TRUE
J 0
(-5675 2550);
DISPLAY 0.872340 (-5675 2550);
DISPLAY INVISIBLE (-5675 2550);
FORCEPROP 1 LAST PATH I44
J 0
(-6002 2675);
DISPLAY 0.872340 (-6002 2675);
PAINT GREEN (-6002 2675);
DISPLAY INVISIBLE (-6002 2675);
FORCEADD TAP..1
(-6000 2725);
FORCEPROP 3 LASTPIN (-6050 2725) SIG_NAME M_K_CPU1_SB_DQ<12>
J 0
(-6040 2735);
DISPLAY 0.659574 (-6040 2735);
PAINT MONO (-6040 2735);
DISPLAY INVISIBLE (-6040 2735);
FORCEPROP 1 LASTPIN (-6050 2725) BN 12
J 0
(-6062 2733);
DISPLAY 0.489362 (-6062 2733);
PAINT GREEN (-6062 2733);
FORCEPROP 2 LAST CDS_LIB mstr_standard
J 0
(-6000 2725);
DISPLAY 0.723404 (-6000 2725);
PAINT MONO (-6000 2725);
DISPLAY INVISIBLE (-6000 2725);
FORCEPROP 1 LAST BODY_TYPE PLUMBING
J 0
(-6000 2775);
DISPLAY 0.872340 (-6000 2775);
PAINT GREEN (-6000 2775);
DISPLAY INVISIBLE (-6000 2775);
FORCEPROP 1 LAST HDL_TAP TRUE
J 0
(-5675 2600);
DISPLAY 0.872340 (-5675 2600);
DISPLAY INVISIBLE (-5675 2600);
FORCEPROP 1 LAST PATH I45
J 0
(-6002 2725);
DISPLAY 0.872340 (-6002 2725);
PAINT GREEN (-6002 2725);
DISPLAY INVISIBLE (-6002 2725);
FORCEADD TAP..1
(-6000 2775);
FORCEPROP 3 LASTPIN (-6050 2775) SIG_NAME M_K_CPU1_SB_DQ<13>
J 0
(-6040 2785);
DISPLAY 0.659574 (-6040 2785);
PAINT MONO (-6040 2785);
DISPLAY INVISIBLE (-6040 2785);
FORCEPROP 1 LASTPIN (-6050 2775) BN 13
J 0
(-6062 2783);
DISPLAY 0.489362 (-6062 2783);
PAINT GREEN (-6062 2783);
FORCEPROP 2 LAST CDS_LIB mstr_standard
J 0
(-6000 2775);
DISPLAY 0.723404 (-6000 2775);
PAINT MONO (-6000 2775);
DISPLAY INVISIBLE (-6000 2775);
FORCEPROP 1 LAST BODY_TYPE PLUMBING
J 0
(-6000 2825);
DISPLAY 0.872340 (-6000 2825);
PAINT GREEN (-6000 2825);
DISPLAY INVISIBLE (-6000 2825);
FORCEPROP 1 LAST HDL_TAP TRUE
J 0
(-5675 2650);
DISPLAY 0.872340 (-5675 2650);
DISPLAY INVISIBLE (-5675 2650);
FORCEPROP 1 LAST PATH I46
J 0
(-6002 2775);
DISPLAY 0.872340 (-6002 2775);
PAINT GREEN (-6002 2775);
DISPLAY INVISIBLE (-6002 2775);
FORCEADD TAP..1
(-6000 2825);
FORCEPROP 3 LASTPIN (-6050 2825) SIG_NAME M_K_CPU1_SB_DQ<14>
J 0
(-6040 2835);
DISPLAY 0.659574 (-6040 2835);
PAINT MONO (-6040 2835);
DISPLAY INVISIBLE (-6040 2835);
FORCEPROP 1 LASTPIN (-6050 2825) BN 14
J 0
(-6062 2833);
DISPLAY 0.489362 (-6062 2833);
PAINT GREEN (-6062 2833);
FORCEPROP 2 LAST CDS_LIB mstr_standard
J 0
(-6000 2825);
DISPLAY 0.723404 (-6000 2825);
PAINT MONO (-6000 2825);
DISPLAY INVISIBLE (-6000 2825);
FORCEPROP 1 LAST BODY_TYPE PLUMBING
J 0
(-6000 2875);
DISPLAY 0.872340 (-6000 2875);
PAINT GREEN (-6000 2875);
DISPLAY INVISIBLE (-6000 2875);
FORCEPROP 1 LAST HDL_TAP TRUE
J 0
(-5675 2700);
DISPLAY 0.872340 (-5675 2700);
DISPLAY INVISIBLE (-5675 2700);
FORCEPROP 1 LAST PATH I47
J 0
(-6002 2825);
DISPLAY 0.872340 (-6002 2825);
PAINT GREEN (-6002 2825);
DISPLAY INVISIBLE (-6002 2825);
FORCEADD TAP..1
(-6000 2875);
FORCEPROP 3 LASTPIN (-6050 2875) SIG_NAME M_K_CPU1_SB_DQ<15>
J 0
(-6040 2885);
DISPLAY 0.659574 (-6040 2885);
PAINT MONO (-6040 2885);
DISPLAY INVISIBLE (-6040 2885);
FORCEPROP 1 LASTPIN (-6050 2875) BN 15
J 0
(-6062 2883);
DISPLAY 0.489362 (-6062 2883);
PAINT GREEN (-6062 2883);
FORCEPROP 2 LAST CDS_LIB mstr_standard
J 0
(-6000 2875);
DISPLAY 0.723404 (-6000 2875);
PAINT MONO (-6000 2875);
DISPLAY INVISIBLE (-6000 2875);
FORCEPROP 1 LAST BODY_TYPE PLUMBING
J 0
(-6000 2925);
DISPLAY 0.872340 (-6000 2925);
PAINT GREEN (-6000 2925);
DISPLAY INVISIBLE (-6000 2925);
FORCEPROP 1 LAST HDL_TAP TRUE
J 0
(-5675 2750);
DISPLAY 0.872340 (-5675 2750);
DISPLAY INVISIBLE (-5675 2750);
FORCEPROP 1 LAST PATH I48
J 0
(-6002 2875);
DISPLAY 0.872340 (-6002 2875);
PAINT GREEN (-6002 2875);
DISPLAY INVISIBLE (-6002 2875);
FORCEADD TAP..1
(-6000 2925);
FORCEPROP 3 LASTPIN (-6050 2925) SIG_NAME M_K_CPU1_SB_DQ<16>
J 0
(-6040 2935);
DISPLAY 0.659574 (-6040 2935);
PAINT MONO (-6040 2935);
DISPLAY INVISIBLE (-6040 2935);
FORCEPROP 1 LASTPIN (-6050 2925) BN 16
J 0
(-6062 2933);
DISPLAY 0.489362 (-6062 2933);
PAINT GREEN (-6062 2933);
FORCEPROP 2 LAST CDS_LIB mstr_standard
J 0
(-6000 2925);
DISPLAY 0.723404 (-6000 2925);
PAINT MONO (-6000 2925);
DISPLAY INVISIBLE (-6000 2925);
FORCEPROP 1 LAST BODY_TYPE PLUMBING
J 0
(-6000 2975);
DISPLAY 0.872340 (-6000 2975);
PAINT GREEN (-6000 2975);
DISPLAY INVISIBLE (-6000 2975);
FORCEPROP 1 LAST HDL_TAP TRUE
J 0
(-5675 2800);
DISPLAY 0.872340 (-5675 2800);
DISPLAY INVISIBLE (-5675 2800);
FORCEPROP 1 LAST PATH I49
J 0
(-6002 2925);
DISPLAY 0.872340 (-6002 2925);
PAINT GREEN (-6002 2925);
DISPLAY INVISIBLE (-6002 2925);
FORCEADD TAP..1
(-6000 2975);
FORCEPROP 3 LASTPIN (-6050 2975) SIG_NAME M_K_CPU1_SB_DQ<17>
J 0
(-6040 2985);
DISPLAY 0.659574 (-6040 2985);
PAINT MONO (-6040 2985);
DISPLAY INVISIBLE (-6040 2985);
FORCEPROP 1 LASTPIN (-6050 2975) BN 17
J 0
(-6062 2983);
DISPLAY 0.489362 (-6062 2983);
PAINT GREEN (-6062 2983);
FORCEPROP 2 LAST CDS_LIB mstr_standard
J 0
(-6000 2975);
DISPLAY 0.723404 (-6000 2975);
PAINT MONO (-6000 2975);
DISPLAY INVISIBLE (-6000 2975);
FORCEPROP 1 LAST BODY_TYPE PLUMBING
J 0
(-6000 3025);
DISPLAY 0.872340 (-6000 3025);
PAINT GREEN (-6000 3025);
DISPLAY INVISIBLE (-6000 3025);
FORCEPROP 1 LAST HDL_TAP TRUE
J 0
(-5675 2850);
DISPLAY 0.872340 (-5675 2850);
DISPLAY INVISIBLE (-5675 2850);
FORCEPROP 1 LAST PATH I50
J 0
(-6002 2975);
DISPLAY 0.872340 (-6002 2975);
PAINT GREEN (-6002 2975);
DISPLAY INVISIBLE (-6002 2975);
FORCEADD TAP..1
(-6000 3025);
FORCEPROP 3 LASTPIN (-6050 3025) SIG_NAME M_K_CPU1_SB_DQ<18>
J 0
(-6040 3035);
DISPLAY 0.659574 (-6040 3035);
PAINT MONO (-6040 3035);
DISPLAY INVISIBLE (-6040 3035);
FORCEPROP 1 LASTPIN (-6050 3025) BN 18
J 0
(-6062 3033);
DISPLAY 0.489362 (-6062 3033);
PAINT GREEN (-6062 3033);
FORCEPROP 2 LAST CDS_LIB mstr_standard
J 0
(-6000 3025);
DISPLAY 0.723404 (-6000 3025);
PAINT MONO (-6000 3025);
DISPLAY INVISIBLE (-6000 3025);
FORCEPROP 1 LAST BODY_TYPE PLUMBING
J 0
(-6000 3075);
DISPLAY 0.872340 (-6000 3075);
PAINT GREEN (-6000 3075);
DISPLAY INVISIBLE (-6000 3075);
FORCEPROP 1 LAST HDL_TAP TRUE
J 0
(-5675 2900);
DISPLAY 0.872340 (-5675 2900);
DISPLAY INVISIBLE (-5675 2900);
FORCEPROP 1 LAST PATH I51
J 0
(-6002 3025);
DISPLAY 0.872340 (-6002 3025);
PAINT GREEN (-6002 3025);
DISPLAY INVISIBLE (-6002 3025);
FORCEADD TAP..1
(-6000 3075);
FORCEPROP 3 LASTPIN (-6050 3075) SIG_NAME M_K_CPU1_SB_DQ<19>
J 0
(-6040 3085);
DISPLAY 0.659574 (-6040 3085);
PAINT MONO (-6040 3085);
DISPLAY INVISIBLE (-6040 3085);
FORCEPROP 1 LASTPIN (-6050 3075) BN 19
J 0
(-6062 3083);
DISPLAY 0.489362 (-6062 3083);
PAINT GREEN (-6062 3083);
FORCEPROP 2 LAST CDS_LIB mstr_standard
J 0
(-6000 3075);
DISPLAY 0.723404 (-6000 3075);
PAINT MONO (-6000 3075);
DISPLAY INVISIBLE (-6000 3075);
FORCEPROP 1 LAST BODY_TYPE PLUMBING
J 0
(-6000 3125);
DISPLAY 0.872340 (-6000 3125);
PAINT GREEN (-6000 3125);
DISPLAY INVISIBLE (-6000 3125);
FORCEPROP 1 LAST HDL_TAP TRUE
J 0
(-5675 2950);
DISPLAY 0.872340 (-5675 2950);
DISPLAY INVISIBLE (-5675 2950);
FORCEPROP 1 LAST PATH I52
J 0
(-6002 3075);
DISPLAY 0.872340 (-6002 3075);
PAINT GREEN (-6002 3075);
DISPLAY INVISIBLE (-6002 3075);
FORCEADD TAP..1
(-6000 3125);
FORCEPROP 3 LASTPIN (-6050 3125) SIG_NAME M_K_CPU1_SB_DQ<20>
J 0
(-6040 3135);
DISPLAY 0.659574 (-6040 3135);
PAINT MONO (-6040 3135);
DISPLAY INVISIBLE (-6040 3135);
FORCEPROP 1 LASTPIN (-6050 3125) BN 20
J 0
(-6062 3133);
DISPLAY 0.489362 (-6062 3133);
PAINT GREEN (-6062 3133);
FORCEPROP 2 LAST CDS_LIB mstr_standard
J 0
(-6000 3125);
DISPLAY 0.723404 (-6000 3125);
PAINT MONO (-6000 3125);
DISPLAY INVISIBLE (-6000 3125);
FORCEPROP 1 LAST BODY_TYPE PLUMBING
J 0
(-6000 3175);
DISPLAY 0.872340 (-6000 3175);
PAINT GREEN (-6000 3175);
DISPLAY INVISIBLE (-6000 3175);
FORCEPROP 1 LAST HDL_TAP TRUE
J 0
(-5675 3000);
DISPLAY 0.872340 (-5675 3000);
DISPLAY INVISIBLE (-5675 3000);
FORCEPROP 1 LAST PATH I53
J 0
(-6002 3125);
DISPLAY 0.872340 (-6002 3125);
PAINT GREEN (-6002 3125);
DISPLAY INVISIBLE (-6002 3125);
FORCEADD TAP..1
(-6000 3175);
FORCEPROP 3 LASTPIN (-6050 3175) SIG_NAME M_K_CPU1_SB_DQ<21>
J 0
(-6040 3185);
DISPLAY 0.659574 (-6040 3185);
PAINT MONO (-6040 3185);
DISPLAY INVISIBLE (-6040 3185);
FORCEPROP 1 LASTPIN (-6050 3175) BN 21
J 0
(-6062 3183);
DISPLAY 0.489362 (-6062 3183);
PAINT GREEN (-6062 3183);
FORCEPROP 2 LAST CDS_LIB mstr_standard
J 0
(-6000 3175);
DISPLAY 0.723404 (-6000 3175);
PAINT MONO (-6000 3175);
DISPLAY INVISIBLE (-6000 3175);
FORCEPROP 1 LAST BODY_TYPE PLUMBING
J 0
(-6000 3225);
DISPLAY 0.872340 (-6000 3225);
PAINT GREEN (-6000 3225);
DISPLAY INVISIBLE (-6000 3225);
FORCEPROP 1 LAST HDL_TAP TRUE
J 0
(-5675 3050);
DISPLAY 0.872340 (-5675 3050);
DISPLAY INVISIBLE (-5675 3050);
FORCEPROP 1 LAST PATH I54
J 0
(-6002 3175);
DISPLAY 0.872340 (-6002 3175);
PAINT GREEN (-6002 3175);
DISPLAY INVISIBLE (-6002 3175);
FORCEADD TAP..1
(-6000 3225);
FORCEPROP 3 LASTPIN (-6050 3225) SIG_NAME M_K_CPU1_SB_DQ<22>
J 0
(-6040 3235);
DISPLAY 0.659574 (-6040 3235);
PAINT MONO (-6040 3235);
DISPLAY INVISIBLE (-6040 3235);
FORCEPROP 1 LASTPIN (-6050 3225) BN 22
J 0
(-6062 3233);
DISPLAY 0.489362 (-6062 3233);
PAINT GREEN (-6062 3233);
FORCEPROP 2 LAST CDS_LIB mstr_standard
J 0
(-6000 3225);
DISPLAY 0.723404 (-6000 3225);
PAINT MONO (-6000 3225);
DISPLAY INVISIBLE (-6000 3225);
FORCEPROP 1 LAST BODY_TYPE PLUMBING
J 0
(-6000 3275);
DISPLAY 0.872340 (-6000 3275);
PAINT GREEN (-6000 3275);
DISPLAY INVISIBLE (-6000 3275);
FORCEPROP 1 LAST HDL_TAP TRUE
J 0
(-5675 3100);
DISPLAY 0.872340 (-5675 3100);
DISPLAY INVISIBLE (-5675 3100);
FORCEPROP 1 LAST PATH I55
J 0
(-6002 3225);
DISPLAY 0.872340 (-6002 3225);
PAINT GREEN (-6002 3225);
DISPLAY INVISIBLE (-6002 3225);
FORCEADD TAP..1
(-6000 3275);
FORCEPROP 3 LASTPIN (-6050 3275) SIG_NAME M_K_CPU1_SB_DQ<23>
J 0
(-6040 3285);
DISPLAY 0.659574 (-6040 3285);
PAINT MONO (-6040 3285);
DISPLAY INVISIBLE (-6040 3285);
FORCEPROP 1 LASTPIN (-6050 3275) BN 23
J 0
(-6062 3283);
DISPLAY 0.489362 (-6062 3283);
PAINT GREEN (-6062 3283);
FORCEPROP 2 LAST CDS_LIB mstr_standard
J 0
(-6000 3275);
DISPLAY 0.723404 (-6000 3275);
PAINT MONO (-6000 3275);
DISPLAY INVISIBLE (-6000 3275);
FORCEPROP 1 LAST BODY_TYPE PLUMBING
J 0
(-6000 3325);
DISPLAY 0.872340 (-6000 3325);
PAINT GREEN (-6000 3325);
DISPLAY INVISIBLE (-6000 3325);
FORCEPROP 1 LAST HDL_TAP TRUE
J 0
(-5675 3150);
DISPLAY 0.872340 (-5675 3150);
DISPLAY INVISIBLE (-5675 3150);
FORCEPROP 1 LAST PATH I56
J 0
(-6002 3275);
DISPLAY 0.872340 (-6002 3275);
PAINT GREEN (-6002 3275);
DISPLAY INVISIBLE (-6002 3275);
FORCEADD TAP..1
(-6000 3325);
FORCEPROP 3 LASTPIN (-6050 3325) SIG_NAME M_K_CPU1_SB_DQ<24>
J 0
(-6040 3335);
DISPLAY 0.659574 (-6040 3335);
PAINT MONO (-6040 3335);
DISPLAY INVISIBLE (-6040 3335);
FORCEPROP 1 LASTPIN (-6050 3325) BN 24
J 0
(-6062 3333);
DISPLAY 0.489362 (-6062 3333);
PAINT GREEN (-6062 3333);
FORCEPROP 2 LAST CDS_LIB mstr_standard
J 0
(-6000 3325);
DISPLAY 0.723404 (-6000 3325);
PAINT MONO (-6000 3325);
DISPLAY INVISIBLE (-6000 3325);
FORCEPROP 1 LAST BODY_TYPE PLUMBING
J 0
(-6000 3375);
DISPLAY 0.872340 (-6000 3375);
PAINT GREEN (-6000 3375);
DISPLAY INVISIBLE (-6000 3375);
FORCEPROP 1 LAST HDL_TAP TRUE
J 0
(-5675 3200);
DISPLAY 0.872340 (-5675 3200);
DISPLAY INVISIBLE (-5675 3200);
FORCEPROP 1 LAST PATH I57
J 0
(-6002 3325);
DISPLAY 0.872340 (-6002 3325);
PAINT GREEN (-6002 3325);
DISPLAY INVISIBLE (-6002 3325);
FORCEADD TAP..1
(-6000 3375);
FORCEPROP 3 LASTPIN (-6050 3375) SIG_NAME M_K_CPU1_SB_DQ<25>
J 0
(-6040 3385);
DISPLAY 0.659574 (-6040 3385);
PAINT MONO (-6040 3385);
DISPLAY INVISIBLE (-6040 3385);
FORCEPROP 1 LASTPIN (-6050 3375) BN 25
J 0
(-6062 3383);
DISPLAY 0.489362 (-6062 3383);
PAINT GREEN (-6062 3383);
FORCEPROP 2 LAST CDS_LIB mstr_standard
J 0
(-6000 3375);
DISPLAY 0.723404 (-6000 3375);
PAINT MONO (-6000 3375);
DISPLAY INVISIBLE (-6000 3375);
FORCEPROP 1 LAST BODY_TYPE PLUMBING
J 0
(-6000 3425);
DISPLAY 0.872340 (-6000 3425);
PAINT GREEN (-6000 3425);
DISPLAY INVISIBLE (-6000 3425);
FORCEPROP 1 LAST HDL_TAP TRUE
J 0
(-5675 3250);
DISPLAY 0.872340 (-5675 3250);
DISPLAY INVISIBLE (-5675 3250);
FORCEPROP 1 LAST PATH I58
J 0
(-6002 3375);
DISPLAY 0.872340 (-6002 3375);
PAINT GREEN (-6002 3375);
DISPLAY INVISIBLE (-6002 3375);
FORCEADD TAP..1
(-6000 3425);
FORCEPROP 3 LASTPIN (-6050 3425) SIG_NAME M_K_CPU1_SB_DQ<26>
J 0
(-6040 3435);
DISPLAY 0.659574 (-6040 3435);
PAINT MONO (-6040 3435);
DISPLAY INVISIBLE (-6040 3435);
FORCEPROP 1 LASTPIN (-6050 3425) BN 26
J 0
(-6062 3433);
DISPLAY 0.489362 (-6062 3433);
PAINT GREEN (-6062 3433);
FORCEPROP 2 LAST CDS_LIB mstr_standard
J 0
(-6000 3425);
DISPLAY 0.723404 (-6000 3425);
PAINT MONO (-6000 3425);
DISPLAY INVISIBLE (-6000 3425);
FORCEPROP 1 LAST BODY_TYPE PLUMBING
J 0
(-6000 3475);
DISPLAY 0.872340 (-6000 3475);
PAINT GREEN (-6000 3475);
DISPLAY INVISIBLE (-6000 3475);
FORCEPROP 1 LAST HDL_TAP TRUE
J 0
(-5675 3300);
DISPLAY 0.872340 (-5675 3300);
DISPLAY INVISIBLE (-5675 3300);
FORCEPROP 1 LAST PATH I59
J 0
(-6002 3425);
DISPLAY 0.872340 (-6002 3425);
PAINT GREEN (-6002 3425);
DISPLAY INVISIBLE (-6002 3425);
FORCEADD OFFPAGE..1
(-8550 2825);
FORCEPROP 2 LAST $XR0 108 
J 0
(-8802 2825);
DISPLAY 0.638298 (-8802 2825);
PAINT MONO (-8802 2825);
FORCEPROP 2 LAST CDS_LIB mstr_standard
J 0
(-8550 2825);
DISPLAY 0.808511 (-8550 2825);
DISPLAY INVISIBLE (-8550 2825);
FORCEPROP 1 LAST OFFPAGE TRUE
J 0
(-8225 2700);
DISPLAY 0.872340 (-8225 2700);
PAINT GREEN (-8225 2700);
DISPLAY INVISIBLE (-8225 2700);
FORCEPROP 1 LAST COMMENT_BODY TRUE
J 0
(-8425 2725);
DISPLAY 0.872340 (-8425 2725);
PAINT GREEN (-8425 2725);
DISPLAY INVISIBLE (-8425 2725);
FORCEPROP 2 LAST PATH I6
J 0
(-8800 2875);
DISPLAY 1.021277 (-8800 2875);
DISPLAY INVISIBLE (-8800 2875);
FORCEADD TAP..1
(-6000 3475);
FORCEPROP 3 LASTPIN (-6050 3475) SIG_NAME M_K_CPU1_SB_DQ<27>
J 0
(-6040 3485);
DISPLAY 0.659574 (-6040 3485);
PAINT MONO (-6040 3485);
DISPLAY INVISIBLE (-6040 3485);
FORCEPROP 1 LASTPIN (-6050 3475) BN 27
J 0
(-6062 3483);
DISPLAY 0.489362 (-6062 3483);
PAINT GREEN (-6062 3483);
FORCEPROP 2 LAST CDS_LIB mstr_standard
J 0
(-6000 3475);
DISPLAY 0.723404 (-6000 3475);
PAINT MONO (-6000 3475);
DISPLAY INVISIBLE (-6000 3475);
FORCEPROP 1 LAST BODY_TYPE PLUMBING
J 0
(-6000 3525);
DISPLAY 0.872340 (-6000 3525);
PAINT GREEN (-6000 3525);
DISPLAY INVISIBLE (-6000 3525);
FORCEPROP 1 LAST HDL_TAP TRUE
J 0
(-5675 3350);
DISPLAY 0.872340 (-5675 3350);
DISPLAY INVISIBLE (-5675 3350);
FORCEPROP 1 LAST PATH I60
J 0
(-6002 3475);
DISPLAY 0.872340 (-6002 3475);
PAINT GREEN (-6002 3475);
DISPLAY INVISIBLE (-6002 3475);
FORCEADD TAP..1
(-6000 3525);
FORCEPROP 3 LASTPIN (-6050 3525) SIG_NAME M_K_CPU1_SB_DQ<28>
J 0
(-6040 3535);
DISPLAY 0.659574 (-6040 3535);
PAINT MONO (-6040 3535);
DISPLAY INVISIBLE (-6040 3535);
FORCEPROP 1 LASTPIN (-6050 3525) BN 28
J 0
(-6062 3533);
DISPLAY 0.489362 (-6062 3533);
PAINT GREEN (-6062 3533);
FORCEPROP 2 LAST CDS_LIB mstr_standard
J 0
(-6000 3525);
DISPLAY 0.723404 (-6000 3525);
PAINT MONO (-6000 3525);
DISPLAY INVISIBLE (-6000 3525);
FORCEPROP 1 LAST BODY_TYPE PLUMBING
J 0
(-6000 3575);
DISPLAY 0.872340 (-6000 3575);
PAINT GREEN (-6000 3575);
DISPLAY INVISIBLE (-6000 3575);
FORCEPROP 1 LAST HDL_TAP TRUE
J 0
(-5675 3400);
DISPLAY 0.872340 (-5675 3400);
DISPLAY INVISIBLE (-5675 3400);
FORCEPROP 1 LAST PATH I61
J 0
(-6002 3525);
DISPLAY 0.872340 (-6002 3525);
PAINT GREEN (-6002 3525);
DISPLAY INVISIBLE (-6002 3525);
FORCEADD TAP..1
(-6000 3575);
FORCEPROP 3 LASTPIN (-6050 3575) SIG_NAME M_K_CPU1_SB_DQ<29>
J 0
(-6040 3585);
DISPLAY 0.659574 (-6040 3585);
PAINT MONO (-6040 3585);
DISPLAY INVISIBLE (-6040 3585);
FORCEPROP 1 LASTPIN (-6050 3575) BN 29
J 0
(-6062 3583);
DISPLAY 0.489362 (-6062 3583);
PAINT GREEN (-6062 3583);
FORCEPROP 2 LAST CDS_LIB mstr_standard
J 0
(-6000 3575);
DISPLAY 0.723404 (-6000 3575);
PAINT MONO (-6000 3575);
DISPLAY INVISIBLE (-6000 3575);
FORCEPROP 1 LAST BODY_TYPE PLUMBING
J 0
(-6000 3625);
DISPLAY 0.872340 (-6000 3625);
PAINT GREEN (-6000 3625);
DISPLAY INVISIBLE (-6000 3625);
FORCEPROP 1 LAST HDL_TAP TRUE
J 0
(-5675 3450);
DISPLAY 0.872340 (-5675 3450);
DISPLAY INVISIBLE (-5675 3450);
FORCEPROP 1 LAST PATH I62
J 0
(-6002 3575);
DISPLAY 0.872340 (-6002 3575);
PAINT GREEN (-6002 3575);
DISPLAY INVISIBLE (-6002 3575);
FORCEADD TAP..1
(-6000 3625);
FORCEPROP 3 LASTPIN (-6050 3625) SIG_NAME M_K_CPU1_SB_DQ<30>
J 0
(-6040 3635);
DISPLAY 0.659574 (-6040 3635);
PAINT MONO (-6040 3635);
DISPLAY INVISIBLE (-6040 3635);
FORCEPROP 1 LASTPIN (-6050 3625) BN 30
J 0
(-6062 3633);
DISPLAY 0.489362 (-6062 3633);
PAINT GREEN (-6062 3633);
FORCEPROP 2 LAST CDS_LIB mstr_standard
J 0
(-6000 3625);
DISPLAY 0.723404 (-6000 3625);
PAINT MONO (-6000 3625);
DISPLAY INVISIBLE (-6000 3625);
FORCEPROP 1 LAST BODY_TYPE PLUMBING
J 0
(-6000 3675);
DISPLAY 0.872340 (-6000 3675);
PAINT GREEN (-6000 3675);
DISPLAY INVISIBLE (-6000 3675);
FORCEPROP 1 LAST HDL_TAP TRUE
J 0
(-5675 3500);
DISPLAY 0.872340 (-5675 3500);
DISPLAY INVISIBLE (-5675 3500);
FORCEPROP 1 LAST PATH I63
J 0
(-6002 3625);
DISPLAY 0.872340 (-6002 3625);
PAINT GREEN (-6002 3625);
DISPLAY INVISIBLE (-6002 3625);
FORCEADD VCC_CORE..1
(-8575 3350);
FORCEPROP 3 LASTPIN (-8575 3300) SIG_NAME P3V3_AUX\g
J 0
(-8565 3310);
DISPLAY 0.659574 (-8565 3310);
PAINT MONO (-8565 3310);
DISPLAY INVISIBLE (-8565 3310);
FORCEPROP 1 LAST HDL_POWER P3V3_AUX
J 1
(-8575 3400);
DISPLAY 0.489362 (-8575 3400);
PAINT GREEN (-8575 3400);
FORCEPROP 2 LAST CDS_LIB mstr_symbols
J 0
(-8575 3350);
PAINT MONO (-8575 3350);
DISPLAY INVISIBLE (-8575 3350);
FORCEPROP 0 LAST VOLTAGE 3.3
J 0
(-8850 3500);
DISPLAY 1.021277 (-8850 3500);
PAINT SKYBLUE (-8850 3500);
DISPLAY INVISIBLE (-8850 3500);
FORCEPROP 2 LAST ROOM PVCCINFAON_CPU1_CTRL
J 0
(-8575 3450);
DISPLAY 0.808511 (-8575 3450);
PAINT RED (-8575 3450);
DISPLAY INVISIBLE (-8575 3450);
FORCEPROP 1 LAST PATH I7
J 0
(-8525 3375);
DISPLAY 0.872340 (-8525 3375);
PAINT AQUA (-8525 3375);
DISPLAY INVISIBLE (-8525 3375);
FORCEADD TAP..1
R 2
(-7700 3675);
FORCEPROP 3 LASTPIN (-7650 3675) SIG_NAME M_K_CPU1_SA_CB<2>
J 0
(-7640 3685);
DISPLAY 0.659574 (-7640 3685);
PAINT MONO (-7640 3685);
DISPLAY INVISIBLE (-7640 3685);
FORCEPROP 1 LASTPIN (-7650 3675) BN 2
J 2
(-7638 3683);
DISPLAY 0.489362 (-7638 3683);
PAINT GREEN (-7638 3683);
FORCEPROP 2 LAST CDS_LIB mstr_standard
J 0
(-7700 3675);
DISPLAY 0.723404 (-7700 3675);
PAINT MONO (-7700 3675);
DISPLAY INVISIBLE (-7700 3675);
FORCEPROP 1 LAST BODY_TYPE PLUMBING
J 2
(-7700 3725);
DISPLAY 0.872340 (-7700 3725);
PAINT GREEN (-7700 3725);
DISPLAY INVISIBLE (-7700 3725);
FORCEPROP 1 LAST HDL_TAP TRUE
J 2
(-8025 3550);
DISPLAY 0.872340 (-8025 3550);
DISPLAY INVISIBLE (-8025 3550);
FORCEPROP 1 LAST PATH I71
J 2
(-7698 3675);
DISPLAY 0.872340 (-7698 3675);
PAINT GREEN (-7698 3675);
DISPLAY INVISIBLE (-7698 3675);
FORCEADD TAP..1
R 2
(-7700 3725);
FORCEPROP 3 LASTPIN (-7650 3725) SIG_NAME M_K_CPU1_SA_CB<3>
J 0
(-7640 3735);
DISPLAY 0.659574 (-7640 3735);
PAINT MONO (-7640 3735);
DISPLAY INVISIBLE (-7640 3735);
FORCEPROP 1 LASTPIN (-7650 3725) BN 3
J 2
(-7638 3733);
DISPLAY 0.489362 (-7638 3733);
PAINT GREEN (-7638 3733);
FORCEPROP 2 LAST CDS_LIB mstr_standard
J 0
(-7700 3725);
DISPLAY 0.723404 (-7700 3725);
PAINT MONO (-7700 3725);
DISPLAY INVISIBLE (-7700 3725);
FORCEPROP 1 LAST BODY_TYPE PLUMBING
J 2
(-7700 3775);
DISPLAY 0.872340 (-7700 3775);
PAINT GREEN (-7700 3775);
DISPLAY INVISIBLE (-7700 3775);
FORCEPROP 1 LAST HDL_TAP TRUE
J 2
(-8025 3600);
DISPLAY 0.872340 (-8025 3600);
DISPLAY INVISIBLE (-8025 3600);
FORCEPROP 1 LAST PATH I72
J 2
(-7698 3725);
DISPLAY 0.872340 (-7698 3725);
PAINT GREEN (-7698 3725);
DISPLAY INVISIBLE (-7698 3725);
FORCEADD TAP..1
R 2
(-7700 3825);
FORCEPROP 3 LASTPIN (-7650 3825) SIG_NAME M_K_CPU1_SA_CB<5>
J 0
(-7640 3835);
DISPLAY 0.659574 (-7640 3835);
PAINT MONO (-7640 3835);
DISPLAY INVISIBLE (-7640 3835);
FORCEPROP 1 LASTPIN (-7650 3825) BN 5
J 2
(-7638 3833);
DISPLAY 0.489362 (-7638 3833);
PAINT GREEN (-7638 3833);
FORCEPROP 2 LAST CDS_LIB mstr_standard
J 0
(-7700 3825);
DISPLAY 0.723404 (-7700 3825);
PAINT MONO (-7700 3825);
DISPLAY INVISIBLE (-7700 3825);
FORCEPROP 1 LAST BODY_TYPE PLUMBING
J 2
(-7700 3875);
DISPLAY 0.872340 (-7700 3875);
PAINT GREEN (-7700 3875);
DISPLAY INVISIBLE (-7700 3875);
FORCEPROP 1 LAST HDL_TAP TRUE
J 2
(-8025 3700);
DISPLAY 0.872340 (-8025 3700);
DISPLAY INVISIBLE (-8025 3700);
FORCEPROP 1 LAST PATH I73
J 2
(-7698 3825);
DISPLAY 0.872340 (-7698 3825);
PAINT GREEN (-7698 3825);
DISPLAY INVISIBLE (-7698 3825);
FORCEADD TAP..1
R 2
(-7700 3875);
FORCEPROP 3 LASTPIN (-7650 3875) SIG_NAME M_K_CPU1_SA_CB<6>
J 0
(-7640 3885);
DISPLAY 0.659574 (-7640 3885);
PAINT MONO (-7640 3885);
DISPLAY INVISIBLE (-7640 3885);
FORCEPROP 1 LASTPIN (-7650 3875) BN 6
J 2
(-7638 3883);
DISPLAY 0.489362 (-7638 3883);
PAINT GREEN (-7638 3883);
FORCEPROP 2 LAST CDS_LIB mstr_standard
J 0
(-7700 3875);
DISPLAY 0.723404 (-7700 3875);
PAINT MONO (-7700 3875);
DISPLAY INVISIBLE (-7700 3875);
FORCEPROP 1 LAST BODY_TYPE PLUMBING
J 2
(-7700 3925);
DISPLAY 0.872340 (-7700 3925);
PAINT GREEN (-7700 3925);
DISPLAY INVISIBLE (-7700 3925);
FORCEPROP 1 LAST HDL_TAP TRUE
J 2
(-8025 3750);
DISPLAY 0.872340 (-8025 3750);
DISPLAY INVISIBLE (-8025 3750);
FORCEPROP 1 LAST PATH I74
J 2
(-7698 3875);
DISPLAY 0.872340 (-7698 3875);
PAINT GREEN (-7698 3875);
DISPLAY INVISIBLE (-7698 3875);
FORCEADD TAP..1
R 2
(-7700 3775);
FORCEPROP 3 LASTPIN (-7650 3775) SIG_NAME M_K_CPU1_SA_CB<4>
J 0
(-7640 3785);
DISPLAY 0.659574 (-7640 3785);
PAINT MONO (-7640 3785);
DISPLAY INVISIBLE (-7640 3785);
FORCEPROP 1 LASTPIN (-7650 3775) BN 4
J 2
(-7638 3783);
DISPLAY 0.489362 (-7638 3783);
PAINT GREEN (-7638 3783);
FORCEPROP 2 LAST CDS_LIB mstr_standard
J 0
(-7700 3775);
DISPLAY 0.723404 (-7700 3775);
PAINT MONO (-7700 3775);
DISPLAY INVISIBLE (-7700 3775);
FORCEPROP 1 LAST BODY_TYPE PLUMBING
J 2
(-7700 3825);
DISPLAY 0.872340 (-7700 3825);
PAINT GREEN (-7700 3825);
DISPLAY INVISIBLE (-7700 3825);
FORCEPROP 1 LAST HDL_TAP TRUE
J 2
(-8025 3650);
DISPLAY 0.872340 (-8025 3650);
DISPLAY INVISIBLE (-8025 3650);
FORCEPROP 1 LAST PATH I75
J 2
(-7698 3775);
DISPLAY 0.872340 (-7698 3775);
PAINT GREEN (-7698 3775);
DISPLAY INVISIBLE (-7698 3775);
FORCEADD TAP..1
R 2
(-7700 3925);
FORCEPROP 3 LASTPIN (-7650 3925) SIG_NAME M_K_CPU1_SA_CB<7>
J 0
(-7640 3935);
DISPLAY 0.659574 (-7640 3935);
PAINT MONO (-7640 3935);
DISPLAY INVISIBLE (-7640 3935);
FORCEPROP 1 LASTPIN (-7650 3925) BN 7
J 2
(-7638 3933);
DISPLAY 0.489362 (-7638 3933);
PAINT GREEN (-7638 3933);
FORCEPROP 2 LAST CDS_LIB mstr_standard
J 0
(-7700 3925);
DISPLAY 0.723404 (-7700 3925);
PAINT MONO (-7700 3925);
DISPLAY INVISIBLE (-7700 3925);
FORCEPROP 1 LAST BODY_TYPE PLUMBING
J 2
(-7700 3975);
DISPLAY 0.872340 (-7700 3975);
PAINT GREEN (-7700 3975);
DISPLAY INVISIBLE (-7700 3975);
FORCEPROP 1 LAST HDL_TAP TRUE
J 2
(-8025 3800);
DISPLAY 0.872340 (-8025 3800);
DISPLAY INVISIBLE (-8025 3800);
FORCEPROP 1 LAST PATH I76
J 2
(-7698 3925);
DISPLAY 0.872340 (-7698 3925);
PAINT GREEN (-7698 3925);
DISPLAY INVISIBLE (-7698 3925);
FORCEADD TAP..1
R 2
(-7700 4625);
FORCEPROP 3 LASTPIN (-7650 4625) SIG_NAME M_K_CPU1_SB_CA<0>
J 0
(-7640 4635);
DISPLAY 0.659574 (-7640 4635);
PAINT MONO (-7640 4635);
DISPLAY INVISIBLE (-7640 4635);
FORCEPROP 1 LASTPIN (-7650 4625) BN 0
J 2
(-7638 4633);
DISPLAY 0.489362 (-7638 4633);
PAINT GREEN (-7638 4633);
FORCEPROP 2 LAST CDS_LIB mstr_standard
J 0
(-7700 4625);
DISPLAY 0.723404 (-7700 4625);
PAINT MONO (-7700 4625);
DISPLAY INVISIBLE (-7700 4625);
FORCEPROP 1 LAST BODY_TYPE PLUMBING
J 2
(-7700 4675);
DISPLAY 0.872340 (-7700 4675);
PAINT GREEN (-7700 4675);
DISPLAY INVISIBLE (-7700 4675);
FORCEPROP 1 LAST HDL_TAP TRUE
J 2
(-8025 4500);
DISPLAY 0.872340 (-8025 4500);
DISPLAY INVISIBLE (-8025 4500);
FORCEPROP 1 LAST PATH I77
J 2
(-7698 4625);
DISPLAY 0.872340 (-7698 4625);
PAINT GREEN (-7698 4625);
DISPLAY INVISIBLE (-7698 4625);
FORCEADD TAP..1
R 2
(-7700 4675);
FORCEPROP 3 LASTPIN (-7650 4675) SIG_NAME M_K_CPU1_SB_CA<1>
J 0
(-7640 4685);
DISPLAY 0.659574 (-7640 4685);
PAINT MONO (-7640 4685);
DISPLAY INVISIBLE (-7640 4685);
FORCEPROP 1 LASTPIN (-7650 4675) BN 1
J 2
(-7638 4683);
DISPLAY 0.489362 (-7638 4683);
PAINT GREEN (-7638 4683);
FORCEPROP 2 LAST CDS_LIB mstr_standard
J 0
(-7700 4675);
DISPLAY 0.723404 (-7700 4675);
PAINT MONO (-7700 4675);
DISPLAY INVISIBLE (-7700 4675);
FORCEPROP 1 LAST BODY_TYPE PLUMBING
J 2
(-7700 4725);
DISPLAY 0.872340 (-7700 4725);
PAINT GREEN (-7700 4725);
DISPLAY INVISIBLE (-7700 4725);
FORCEPROP 1 LAST HDL_TAP TRUE
J 2
(-8025 4550);
DISPLAY 0.872340 (-8025 4550);
DISPLAY INVISIBLE (-8025 4550);
FORCEPROP 1 LAST PATH I78
J 2
(-7698 4675);
DISPLAY 0.872340 (-7698 4675);
PAINT GREEN (-7698 4675);
DISPLAY INVISIBLE (-7698 4675);
FORCEADD TAP..1
R 2
(-7700 4725);
FORCEPROP 3 LASTPIN (-7650 4725) SIG_NAME M_K_CPU1_SB_CA<2>
J 0
(-7640 4735);
DISPLAY 0.659574 (-7640 4735);
PAINT MONO (-7640 4735);
DISPLAY INVISIBLE (-7640 4735);
FORCEPROP 1 LASTPIN (-7650 4725) BN 2
J 2
(-7638 4733);
DISPLAY 0.489362 (-7638 4733);
PAINT GREEN (-7638 4733);
FORCEPROP 2 LAST CDS_LIB mstr_standard
J 0
(-7700 4725);
DISPLAY 0.723404 (-7700 4725);
PAINT MONO (-7700 4725);
DISPLAY INVISIBLE (-7700 4725);
FORCEPROP 1 LAST BODY_TYPE PLUMBING
J 2
(-7700 4775);
DISPLAY 0.872340 (-7700 4775);
PAINT GREEN (-7700 4775);
DISPLAY INVISIBLE (-7700 4775);
FORCEPROP 1 LAST HDL_TAP TRUE
J 2
(-8025 4600);
DISPLAY 0.872340 (-8025 4600);
DISPLAY INVISIBLE (-8025 4600);
FORCEPROP 1 LAST PATH I79
J 2
(-7698 4725);
DISPLAY 0.872340 (-7698 4725);
PAINT GREEN (-7698 4725);
DISPLAY INVISIBLE (-7698 4725);
FORCEADD OFFPAGE..5
(-8150 2975);
FORCEPROP 2 LAST $XR0 47 
J 0
(-8374 2975);
DISPLAY 0.638298 (-8374 2975);
PAINT MONO (-8374 2975);
FORCEPROP 2 LAST CDS_LIB mstr_standard
J 0
(-8150 2975);
DISPLAY INVISIBLE (-8150 2975);
FORCEPROP 1 LAST OFFPAGE TRUE
J 0
(-7825 2850);
DISPLAY 0.872340 (-7825 2850);
PAINT GREEN (-7825 2850);
DISPLAY INVISIBLE (-7825 2850);
FORCEPROP 1 LAST COMMENT_BODY TRUE
J 0
(-8050 2900);
DISPLAY 0.872340 (-8050 2900);
PAINT GREEN (-8050 2900);
DISPLAY INVISIBLE (-8050 2900);
FORCEPROP 2 LAST PATH I8
J 0
(-8350 3025);
DISPLAY 1.021277 (-8350 3025);
DISPLAY INVISIBLE (-8350 3025);
FORCEADD TAP..1
R 2
(-7700 4775);
FORCEPROP 3 LASTPIN (-7650 4775) SIG_NAME M_K_CPU1_SB_CA<3>
J 0
(-7640 4785);
DISPLAY 0.659574 (-7640 4785);
PAINT MONO (-7640 4785);
DISPLAY INVISIBLE (-7640 4785);
FORCEPROP 1 LASTPIN (-7650 4775) BN 3
J 2
(-7638 4783);
DISPLAY 0.489362 (-7638 4783);
PAINT GREEN (-7638 4783);
FORCEPROP 2 LAST CDS_LIB mstr_standard
J 0
(-7700 4775);
DISPLAY 0.723404 (-7700 4775);
PAINT MONO (-7700 4775);
DISPLAY INVISIBLE (-7700 4775);
FORCEPROP 1 LAST BODY_TYPE PLUMBING
J 2
(-7700 4825);
DISPLAY 0.872340 (-7700 4825);
PAINT GREEN (-7700 4825);
DISPLAY INVISIBLE (-7700 4825);
FORCEPROP 1 LAST HDL_TAP TRUE
J 2
(-8025 4650);
DISPLAY 0.872340 (-8025 4650);
DISPLAY INVISIBLE (-8025 4650);
FORCEPROP 1 LAST PATH I80
J 2
(-7698 4775);
DISPLAY 0.872340 (-7698 4775);
PAINT GREEN (-7698 4775);
DISPLAY INVISIBLE (-7698 4775);
FORCEADD TAP..1
R 2
(-7700 4825);
FORCEPROP 3 LASTPIN (-7650 4825) SIG_NAME M_K_CPU1_SB_CA<4>
J 0
(-7640 4835);
DISPLAY 0.659574 (-7640 4835);
PAINT MONO (-7640 4835);
DISPLAY INVISIBLE (-7640 4835);
FORCEPROP 1 LASTPIN (-7650 4825) BN 4
J 2
(-7638 4833);
DISPLAY 0.489362 (-7638 4833);
PAINT GREEN (-7638 4833);
FORCEPROP 2 LAST CDS_LIB mstr_standard
J 0
(-7700 4825);
DISPLAY 0.723404 (-7700 4825);
PAINT MONO (-7700 4825);
DISPLAY INVISIBLE (-7700 4825);
FORCEPROP 1 LAST BODY_TYPE PLUMBING
J 2
(-7700 4875);
DISPLAY 0.872340 (-7700 4875);
PAINT GREEN (-7700 4875);
DISPLAY INVISIBLE (-7700 4875);
FORCEPROP 1 LAST HDL_TAP TRUE
J 2
(-8025 4700);
DISPLAY 0.872340 (-8025 4700);
DISPLAY INVISIBLE (-8025 4700);
FORCEPROP 1 LAST PATH I81
J 2
(-7698 4825);
DISPLAY 0.872340 (-7698 4825);
PAINT GREEN (-7698 4825);
DISPLAY INVISIBLE (-7698 4825);
FORCEADD TAP..1
R 2
(-7700 4925);
FORCEPROP 3 LASTPIN (-7650 4925) SIG_NAME M_K_CPU1_SB_CA<6>
J 0
(-7640 4935);
DISPLAY 0.659574 (-7640 4935);
PAINT MONO (-7640 4935);
DISPLAY INVISIBLE (-7640 4935);
FORCEPROP 1 LASTPIN (-7650 4925) BN 6
J 2
(-7638 4933);
DISPLAY 0.489362 (-7638 4933);
PAINT GREEN (-7638 4933);
FORCEPROP 2 LAST CDS_LIB mstr_standard
J 0
(-7700 4925);
DISPLAY 0.723404 (-7700 4925);
PAINT MONO (-7700 4925);
DISPLAY INVISIBLE (-7700 4925);
FORCEPROP 1 LAST BODY_TYPE PLUMBING
J 2
(-7700 4975);
DISPLAY 0.872340 (-7700 4975);
PAINT GREEN (-7700 4975);
DISPLAY INVISIBLE (-7700 4975);
FORCEPROP 1 LAST HDL_TAP TRUE
J 2
(-8025 4800);
DISPLAY 0.872340 (-8025 4800);
DISPLAY INVISIBLE (-8025 4800);
FORCEPROP 1 LAST PATH I82
J 2
(-7698 4925);
DISPLAY 0.872340 (-7698 4925);
PAINT GREEN (-7698 4925);
DISPLAY INVISIBLE (-7698 4925);
FORCEADD TAP..1
R 2
(-7700 4875);
FORCEPROP 3 LASTPIN (-7650 4875) SIG_NAME M_K_CPU1_SB_CA<5>
J 0
(-7640 4885);
DISPLAY 0.659574 (-7640 4885);
PAINT MONO (-7640 4885);
DISPLAY INVISIBLE (-7640 4885);
FORCEPROP 1 LASTPIN (-7650 4875) BN 5
J 2
(-7638 4883);
DISPLAY 0.489362 (-7638 4883);
PAINT GREEN (-7638 4883);
FORCEPROP 2 LAST CDS_LIB mstr_standard
J 0
(-7700 4875);
DISPLAY 0.723404 (-7700 4875);
PAINT MONO (-7700 4875);
DISPLAY INVISIBLE (-7700 4875);
FORCEPROP 1 LAST BODY_TYPE PLUMBING
J 2
(-7700 4925);
DISPLAY 0.872340 (-7700 4925);
PAINT GREEN (-7700 4925);
DISPLAY INVISIBLE (-7700 4925);
FORCEPROP 1 LAST HDL_TAP TRUE
J 2
(-8025 4750);
DISPLAY 0.872340 (-8025 4750);
DISPLAY INVISIBLE (-8025 4750);
FORCEPROP 1 LAST PATH I83
J 2
(-7698 4875);
DISPLAY 0.872340 (-7698 4875);
PAINT GREEN (-7698 4875);
DISPLAY INVISIBLE (-7698 4875);
FORCEADD TAP..1
R 2
(-7700 5075);
FORCEPROP 3 LASTPIN (-7650 5075) SIG_NAME M_K_CPU1_SA_CA<1>
J 0
(-7640 5085);
DISPLAY 0.659574 (-7640 5085);
PAINT MONO (-7640 5085);
DISPLAY INVISIBLE (-7640 5085);
FORCEPROP 1 LASTPIN (-7650 5075) BN 1
J 2
(-7638 5083);
DISPLAY 0.489362 (-7638 5083);
PAINT GREEN (-7638 5083);
FORCEPROP 2 LAST CDS_LIB mstr_standard
J 0
(-7700 5075);
DISPLAY 0.723404 (-7700 5075);
PAINT MONO (-7700 5075);
DISPLAY INVISIBLE (-7700 5075);
FORCEPROP 1 LAST BODY_TYPE PLUMBING
J 2
(-7700 5125);
DISPLAY 0.872340 (-7700 5125);
PAINT GREEN (-7700 5125);
DISPLAY INVISIBLE (-7700 5125);
FORCEPROP 1 LAST HDL_TAP TRUE
J 2
(-8025 4950);
DISPLAY 0.872340 (-8025 4950);
DISPLAY INVISIBLE (-8025 4950);
FORCEPROP 1 LAST PATH I84
J 2
(-7698 5075);
DISPLAY 0.872340 (-7698 5075);
PAINT GREEN (-7698 5075);
DISPLAY INVISIBLE (-7698 5075);
FORCEADD TAP..1
R 2
(-7700 5125);
FORCEPROP 3 LASTPIN (-7650 5125) SIG_NAME M_K_CPU1_SA_CA<2>
J 0
(-7640 5135);
DISPLAY 0.659574 (-7640 5135);
PAINT MONO (-7640 5135);
DISPLAY INVISIBLE (-7640 5135);
FORCEPROP 1 LASTPIN (-7650 5125) BN 2
J 2
(-7638 5133);
DISPLAY 0.489362 (-7638 5133);
PAINT GREEN (-7638 5133);
FORCEPROP 2 LAST CDS_LIB mstr_standard
J 0
(-7700 5125);
DISPLAY 0.723404 (-7700 5125);
PAINT MONO (-7700 5125);
DISPLAY INVISIBLE (-7700 5125);
FORCEPROP 1 LAST BODY_TYPE PLUMBING
J 2
(-7700 5175);
DISPLAY 0.872340 (-7700 5175);
PAINT GREEN (-7700 5175);
DISPLAY INVISIBLE (-7700 5175);
FORCEPROP 1 LAST HDL_TAP TRUE
J 2
(-8025 5000);
DISPLAY 0.872340 (-8025 5000);
DISPLAY INVISIBLE (-8025 5000);
FORCEPROP 1 LAST PATH I85
J 2
(-7698 5125);
DISPLAY 0.872340 (-7698 5125);
PAINT GREEN (-7698 5125);
DISPLAY INVISIBLE (-7698 5125);
FORCEADD TAP..1
R 2
(-7700 5175);
FORCEPROP 3 LASTPIN (-7650 5175) SIG_NAME M_K_CPU1_SA_CA<3>
J 0
(-7640 5185);
DISPLAY 0.659574 (-7640 5185);
PAINT MONO (-7640 5185);
DISPLAY INVISIBLE (-7640 5185);
FORCEPROP 1 LASTPIN (-7650 5175) BN 3
J 2
(-7638 5183);
DISPLAY 0.489362 (-7638 5183);
PAINT GREEN (-7638 5183);
FORCEPROP 2 LAST CDS_LIB mstr_standard
J 0
(-7700 5175);
DISPLAY 0.723404 (-7700 5175);
PAINT MONO (-7700 5175);
DISPLAY INVISIBLE (-7700 5175);
FORCEPROP 1 LAST BODY_TYPE PLUMBING
J 2
(-7700 5225);
DISPLAY 0.872340 (-7700 5225);
PAINT GREEN (-7700 5225);
DISPLAY INVISIBLE (-7700 5225);
FORCEPROP 1 LAST HDL_TAP TRUE
J 2
(-8025 5050);
DISPLAY 0.872340 (-8025 5050);
DISPLAY INVISIBLE (-8025 5050);
FORCEPROP 1 LAST PATH I86
J 2
(-7698 5175);
DISPLAY 0.872340 (-7698 5175);
PAINT GREEN (-7698 5175);
DISPLAY INVISIBLE (-7698 5175);
FORCEADD TAP..1
R 2
(-7700 5025);
FORCEPROP 3 LASTPIN (-7650 5025) SIG_NAME M_K_CPU1_SA_CA<0>
J 0
(-7640 5035);
DISPLAY 0.659574 (-7640 5035);
PAINT MONO (-7640 5035);
DISPLAY INVISIBLE (-7640 5035);
FORCEPROP 1 LASTPIN (-7650 5025) BN 0
J 2
(-7638 5033);
DISPLAY 0.489362 (-7638 5033);
PAINT GREEN (-7638 5033);
FORCEPROP 2 LAST CDS_LIB mstr_standard
J 0
(-7700 5025);
DISPLAY 0.723404 (-7700 5025);
PAINT MONO (-7700 5025);
DISPLAY INVISIBLE (-7700 5025);
FORCEPROP 1 LAST BODY_TYPE PLUMBING
J 2
(-7700 5075);
DISPLAY 0.872340 (-7700 5075);
PAINT GREEN (-7700 5075);
DISPLAY INVISIBLE (-7700 5075);
FORCEPROP 1 LAST HDL_TAP TRUE
J 2
(-8025 4900);
DISPLAY 0.872340 (-8025 4900);
DISPLAY INVISIBLE (-8025 4900);
FORCEPROP 1 LAST PATH I87
J 2
(-7698 5025);
DISPLAY 0.872340 (-7698 5025);
PAINT GREEN (-7698 5025);
DISPLAY INVISIBLE (-7698 5025);
FORCEADD TAP..1
R 2
(-7700 5275);
FORCEPROP 3 LASTPIN (-7650 5275) SIG_NAME M_K_CPU1_SA_CA<5>
J 0
(-7640 5285);
DISPLAY 0.659574 (-7640 5285);
PAINT MONO (-7640 5285);
DISPLAY INVISIBLE (-7640 5285);
FORCEPROP 1 LASTPIN (-7650 5275) BN 5
J 2
(-7638 5283);
DISPLAY 0.489362 (-7638 5283);
PAINT GREEN (-7638 5283);
FORCEPROP 2 LAST CDS_LIB mstr_standard
J 0
(-7700 5275);
DISPLAY 0.723404 (-7700 5275);
PAINT MONO (-7700 5275);
DISPLAY INVISIBLE (-7700 5275);
FORCEPROP 1 LAST BODY_TYPE PLUMBING
J 2
(-7700 5325);
DISPLAY 0.872340 (-7700 5325);
PAINT GREEN (-7700 5325);
DISPLAY INVISIBLE (-7700 5325);
FORCEPROP 1 LAST HDL_TAP TRUE
J 2
(-8025 5150);
DISPLAY 0.872340 (-8025 5150);
DISPLAY INVISIBLE (-8025 5150);
FORCEPROP 1 LAST PATH I88
J 2
(-7698 5275);
DISPLAY 0.872340 (-7698 5275);
PAINT GREEN (-7698 5275);
DISPLAY INVISIBLE (-7698 5275);
FORCEADD TAP..1
R 2
(-7700 5325);
FORCEPROP 3 LASTPIN (-7650 5325) SIG_NAME M_K_CPU1_SA_CA<6>
J 0
(-7640 5335);
DISPLAY 0.659574 (-7640 5335);
PAINT MONO (-7640 5335);
DISPLAY INVISIBLE (-7640 5335);
FORCEPROP 1 LASTPIN (-7650 5325) BN 6
J 2
(-7638 5333);
DISPLAY 0.489362 (-7638 5333);
PAINT GREEN (-7638 5333);
FORCEPROP 2 LAST CDS_LIB mstr_standard
J 0
(-7700 5325);
DISPLAY 0.723404 (-7700 5325);
PAINT MONO (-7700 5325);
DISPLAY INVISIBLE (-7700 5325);
FORCEPROP 1 LAST BODY_TYPE PLUMBING
J 2
(-7700 5375);
DISPLAY 0.872340 (-7700 5375);
PAINT GREEN (-7700 5375);
DISPLAY INVISIBLE (-7700 5375);
FORCEPROP 1 LAST HDL_TAP TRUE
J 2
(-8025 5200);
DISPLAY 0.872340 (-8025 5200);
DISPLAY INVISIBLE (-8025 5200);
FORCEPROP 1 LAST PATH I89
J 2
(-7698 5325);
DISPLAY 0.872340 (-7698 5325);
PAINT GREEN (-7698 5325);
DISPLAY INVISIBLE (-7698 5325);
FORCEADD OFFPAGE..1
(-8150 3025);
FORCEPROP 2 LAST $XR0 47 
J 0
(-8401 3025);
DISPLAY 0.638298 (-8401 3025);
PAINT MONO (-8401 3025);
FORCEPROP 2 LAST CDS_LIB mstr_standard
J 0
(-8150 3025);
DISPLAY 0.808511 (-8150 3025);
DISPLAY INVISIBLE (-8150 3025);
FORCEPROP 1 LAST OFFPAGE TRUE
J 0
(-7825 2900);
DISPLAY 0.872340 (-7825 2900);
PAINT GREEN (-7825 2900);
DISPLAY INVISIBLE (-7825 2900);
FORCEPROP 1 LAST COMMENT_BODY TRUE
J 0
(-8025 2925);
DISPLAY 0.872340 (-8025 2925);
PAINT GREEN (-8025 2925);
DISPLAY INVISIBLE (-8025 2925);
FORCEPROP 2 LAST PATH I9
J 0
(-8350 3075);
DISPLAY 1.021277 (-8350 3075);
DISPLAY INVISIBLE (-8350 3075);
FORCEADD TAP..1
R 2
(-7700 5225);
FORCEPROP 3 LASTPIN (-7650 5225) SIG_NAME M_K_CPU1_SA_CA<4>
J 0
(-7640 5235);
DISPLAY 0.659574 (-7640 5235);
PAINT MONO (-7640 5235);
DISPLAY INVISIBLE (-7640 5235);
FORCEPROP 1 LASTPIN (-7650 5225) BN 4
J 2
(-7638 5233);
DISPLAY 0.489362 (-7638 5233);
PAINT GREEN (-7638 5233);
FORCEPROP 2 LAST CDS_LIB mstr_standard
J 0
(-7700 5225);
DISPLAY 0.723404 (-7700 5225);
PAINT MONO (-7700 5225);
DISPLAY INVISIBLE (-7700 5225);
FORCEPROP 1 LAST BODY_TYPE PLUMBING
J 2
(-7700 5275);
DISPLAY 0.872340 (-7700 5275);
PAINT GREEN (-7700 5275);
DISPLAY INVISIBLE (-7700 5275);
FORCEPROP 1 LAST HDL_TAP TRUE
J 2
(-8025 5100);
DISPLAY 0.872340 (-8025 5100);
DISPLAY INVISIBLE (-8025 5100);
FORCEPROP 1 LAST PATH I90
J 2
(-7698 5225);
DISPLAY 0.872340 (-7698 5225);
PAINT GREEN (-7698 5225);
DISPLAY INVISIBLE (-7698 5225);
FORCEADD TAP..1
(-6000 3675);
FORCEPROP 3 LASTPIN (-6050 3675) SIG_NAME M_K_CPU1_SB_DQ<31>
J 0
(-6040 3685);
DISPLAY 0.659574 (-6040 3685);
PAINT MONO (-6040 3685);
DISPLAY INVISIBLE (-6040 3685);
FORCEPROP 1 LASTPIN (-6050 3675) BN 31
J 0
(-6062 3683);
DISPLAY 0.489362 (-6062 3683);
PAINT GREEN (-6062 3683);
FORCEPROP 2 LAST CDS_LIB mstr_standard
J 0
(-6000 3675);
DISPLAY 0.723404 (-6000 3675);
PAINT MONO (-6000 3675);
DISPLAY INVISIBLE (-6000 3675);
FORCEPROP 1 LAST BODY_TYPE PLUMBING
J 0
(-6000 3725);
DISPLAY 0.872340 (-6000 3725);
PAINT GREEN (-6000 3725);
DISPLAY INVISIBLE (-6000 3725);
FORCEPROP 1 LAST HDL_TAP TRUE
J 0
(-5675 3550);
DISPLAY 0.872340 (-5675 3550);
DISPLAY INVISIBLE (-5675 3550);
FORCEPROP 1 LAST PATH I91
J 0
(-6002 3675);
DISPLAY 0.872340 (-6002 3675);
PAINT GREEN (-6002 3675);
DISPLAY INVISIBLE (-6002 3675);
FORCEADD TAP..1
(-6000 3775);
FORCEPROP 3 LASTPIN (-6050 3775) SIG_NAME M_K_CPU1_SA_DQ<0>
J 0
(-6040 3785);
DISPLAY 0.659574 (-6040 3785);
PAINT MONO (-6040 3785);
DISPLAY INVISIBLE (-6040 3785);
FORCEPROP 1 LASTPIN (-6050 3775) BN 0
J 0
(-6062 3783);
DISPLAY 0.489362 (-6062 3783);
PAINT GREEN (-6062 3783);
FORCEPROP 2 LAST CDS_LIB mstr_standard
J 0
(-6000 3775);
DISPLAY 0.723404 (-6000 3775);
PAINT MONO (-6000 3775);
DISPLAY INVISIBLE (-6000 3775);
FORCEPROP 1 LAST BODY_TYPE PLUMBING
J 0
(-6000 3825);
DISPLAY 0.872340 (-6000 3825);
PAINT GREEN (-6000 3825);
DISPLAY INVISIBLE (-6000 3825);
FORCEPROP 1 LAST HDL_TAP TRUE
J 0
(-5675 3650);
DISPLAY 0.872340 (-5675 3650);
DISPLAY INVISIBLE (-5675 3650);
FORCEPROP 1 LAST PATH I92
J 0
(-6002 3775);
DISPLAY 0.872340 (-6002 3775);
PAINT GREEN (-6002 3775);
DISPLAY INVISIBLE (-6002 3775);
FORCEADD TAP..1
(-6000 3825);
FORCEPROP 3 LASTPIN (-6050 3825) SIG_NAME M_K_CPU1_SA_DQ<1>
J 0
(-6040 3835);
DISPLAY 0.659574 (-6040 3835);
PAINT MONO (-6040 3835);
DISPLAY INVISIBLE (-6040 3835);
FORCEPROP 1 LASTPIN (-6050 3825) BN 1
J 0
(-6062 3833);
DISPLAY 0.489362 (-6062 3833);
PAINT GREEN (-6062 3833);
FORCEPROP 2 LAST CDS_LIB mstr_standard
J 0
(-6000 3825);
DISPLAY 0.723404 (-6000 3825);
PAINT MONO (-6000 3825);
DISPLAY INVISIBLE (-6000 3825);
FORCEPROP 1 LAST BODY_TYPE PLUMBING
J 0
(-6000 3875);
DISPLAY 0.872340 (-6000 3875);
PAINT GREEN (-6000 3875);
DISPLAY INVISIBLE (-6000 3875);
FORCEPROP 1 LAST HDL_TAP TRUE
J 0
(-5675 3700);
DISPLAY 0.872340 (-5675 3700);
DISPLAY INVISIBLE (-5675 3700);
FORCEPROP 1 LAST PATH I93
J 0
(-6002 3825);
DISPLAY 0.872340 (-6002 3825);
PAINT GREEN (-6002 3825);
DISPLAY INVISIBLE (-6002 3825);
FORCEADD TAP..1
(-6000 3875);
FORCEPROP 3 LASTPIN (-6050 3875) SIG_NAME M_K_CPU1_SA_DQ<2>
J 0
(-6040 3885);
DISPLAY 0.659574 (-6040 3885);
PAINT MONO (-6040 3885);
DISPLAY INVISIBLE (-6040 3885);
FORCEPROP 1 LASTPIN (-6050 3875) BN 2
J 0
(-6062 3883);
DISPLAY 0.489362 (-6062 3883);
PAINT GREEN (-6062 3883);
FORCEPROP 2 LAST CDS_LIB mstr_standard
J 0
(-6000 3875);
DISPLAY 0.723404 (-6000 3875);
PAINT MONO (-6000 3875);
DISPLAY INVISIBLE (-6000 3875);
FORCEPROP 1 LAST BODY_TYPE PLUMBING
J 0
(-6000 3925);
DISPLAY 0.872340 (-6000 3925);
PAINT GREEN (-6000 3925);
DISPLAY INVISIBLE (-6000 3925);
FORCEPROP 1 LAST HDL_TAP TRUE
J 0
(-5675 3750);
DISPLAY 0.872340 (-5675 3750);
DISPLAY INVISIBLE (-5675 3750);
FORCEPROP 1 LAST PATH I94
J 0
(-6002 3875);
DISPLAY 0.872340 (-6002 3875);
PAINT GREEN (-6002 3875);
DISPLAY INVISIBLE (-6002 3875);
FORCEADD TAP..1
(-6000 3925);
FORCEPROP 3 LASTPIN (-6050 3925) SIG_NAME M_K_CPU1_SA_DQ<3>
J 0
(-6040 3935);
DISPLAY 0.659574 (-6040 3935);
PAINT MONO (-6040 3935);
DISPLAY INVISIBLE (-6040 3935);
FORCEPROP 1 LASTPIN (-6050 3925) BN 3
J 0
(-6062 3933);
DISPLAY 0.489362 (-6062 3933);
PAINT GREEN (-6062 3933);
FORCEPROP 2 LAST CDS_LIB mstr_standard
J 0
(-6000 3925);
DISPLAY 0.723404 (-6000 3925);
PAINT MONO (-6000 3925);
DISPLAY INVISIBLE (-6000 3925);
FORCEPROP 1 LAST BODY_TYPE PLUMBING
J 0
(-6000 3975);
DISPLAY 0.872340 (-6000 3975);
PAINT GREEN (-6000 3975);
DISPLAY INVISIBLE (-6000 3975);
FORCEPROP 1 LAST HDL_TAP TRUE
J 0
(-5675 3800);
DISPLAY 0.872340 (-5675 3800);
DISPLAY INVISIBLE (-5675 3800);
FORCEPROP 1 LAST PATH I95
J 0
(-6002 3925);
DISPLAY 0.872340 (-6002 3925);
PAINT GREEN (-6002 3925);
DISPLAY INVISIBLE (-6002 3925);
FORCEADD TAP..1
(-6000 3975);
FORCEPROP 3 LASTPIN (-6050 3975) SIG_NAME M_K_CPU1_SA_DQ<4>
J 0
(-6040 3985);
DISPLAY 0.659574 (-6040 3985);
PAINT MONO (-6040 3985);
DISPLAY INVISIBLE (-6040 3985);
FORCEPROP 1 LASTPIN (-6050 3975) BN 4
J 0
(-6062 3983);
DISPLAY 0.489362 (-6062 3983);
PAINT GREEN (-6062 3983);
FORCEPROP 2 LAST CDS_LIB mstr_standard
J 0
(-6000 3975);
DISPLAY 0.723404 (-6000 3975);
PAINT MONO (-6000 3975);
DISPLAY INVISIBLE (-6000 3975);
FORCEPROP 1 LAST BODY_TYPE PLUMBING
J 0
(-6000 4025);
DISPLAY 0.872340 (-6000 4025);
PAINT GREEN (-6000 4025);
DISPLAY INVISIBLE (-6000 4025);
FORCEPROP 1 LAST HDL_TAP TRUE
J 0
(-5675 3850);
DISPLAY 0.872340 (-5675 3850);
DISPLAY INVISIBLE (-5675 3850);
FORCEPROP 1 LAST PATH I96
J 0
(-6002 3975);
DISPLAY 0.872340 (-6002 3975);
PAINT GREEN (-6002 3975);
DISPLAY INVISIBLE (-6002 3975);
FORCEADD TAP..1
(-6000 4025);
FORCEPROP 3 LASTPIN (-6050 4025) SIG_NAME M_K_CPU1_SA_DQ<5>
J 0
(-6040 4035);
DISPLAY 0.659574 (-6040 4035);
PAINT MONO (-6040 4035);
DISPLAY INVISIBLE (-6040 4035);
FORCEPROP 1 LASTPIN (-6050 4025) BN 5
J 0
(-6062 4033);
DISPLAY 0.489362 (-6062 4033);
PAINT GREEN (-6062 4033);
FORCEPROP 2 LAST CDS_LIB mstr_standard
J 0
(-6000 4025);
DISPLAY 0.723404 (-6000 4025);
PAINT MONO (-6000 4025);
DISPLAY INVISIBLE (-6000 4025);
FORCEPROP 1 LAST BODY_TYPE PLUMBING
J 0
(-6000 4075);
DISPLAY 0.872340 (-6000 4075);
PAINT GREEN (-6000 4075);
DISPLAY INVISIBLE (-6000 4075);
FORCEPROP 1 LAST HDL_TAP TRUE
J 0
(-5675 3900);
DISPLAY 0.872340 (-5675 3900);
DISPLAY INVISIBLE (-5675 3900);
FORCEPROP 1 LAST PATH I97
J 0
(-6002 4025);
DISPLAY 0.872340 (-6002 4025);
PAINT GREEN (-6002 4025);
DISPLAY INVISIBLE (-6002 4025);
FORCEADD TAP..1
(-6000 4075);
FORCEPROP 3 LASTPIN (-6050 4075) SIG_NAME M_K_CPU1_SA_DQ<6>
J 0
(-6040 4085);
DISPLAY 0.659574 (-6040 4085);
PAINT MONO (-6040 4085);
DISPLAY INVISIBLE (-6040 4085);
FORCEPROP 1 LASTPIN (-6050 4075) BN 6
J 0
(-6062 4083);
DISPLAY 0.489362 (-6062 4083);
PAINT GREEN (-6062 4083);
FORCEPROP 2 LAST CDS_LIB mstr_standard
J 0
(-6000 4075);
DISPLAY 0.723404 (-6000 4075);
PAINT MONO (-6000 4075);
DISPLAY INVISIBLE (-6000 4075);
FORCEPROP 1 LAST BODY_TYPE PLUMBING
J 0
(-6000 4125);
DISPLAY 0.872340 (-6000 4125);
PAINT GREEN (-6000 4125);
DISPLAY INVISIBLE (-6000 4125);
FORCEPROP 1 LAST HDL_TAP TRUE
J 0
(-5675 3950);
DISPLAY 0.872340 (-5675 3950);
DISPLAY INVISIBLE (-5675 3950);
FORCEPROP 1 LAST PATH I98
J 0
(-6002 4075);
DISPLAY 0.872340 (-6002 4075);
PAINT GREEN (-6002 4075);
DISPLAY INVISIBLE (-6002 4075);
FORCEADD TAP..1
(-6000 4125);
FORCEPROP 3 LASTPIN (-6050 4125) SIG_NAME M_K_CPU1_SA_DQ<7>
J 0
(-6040 4135);
DISPLAY 0.659574 (-6040 4135);
PAINT MONO (-6040 4135);
DISPLAY INVISIBLE (-6040 4135);
FORCEPROP 1 LASTPIN (-6050 4125) BN 7
J 0
(-6062 4133);
DISPLAY 0.489362 (-6062 4133);
PAINT GREEN (-6062 4133);
FORCEPROP 2 LAST CDS_LIB mstr_standard
J 0
(-6000 4125);
DISPLAY 0.723404 (-6000 4125);
PAINT MONO (-6000 4125);
DISPLAY INVISIBLE (-6000 4125);
FORCEPROP 1 LAST BODY_TYPE PLUMBING
J 0
(-6000 4175);
DISPLAY 0.872340 (-6000 4175);
PAINT GREEN (-6000 4175);
DISPLAY INVISIBLE (-6000 4175);
FORCEPROP 1 LAST HDL_TAP TRUE
J 0
(-5675 4000);
DISPLAY 0.872340 (-5675 4000);
DISPLAY INVISIBLE (-5675 4000);
FORCEPROP 1 LAST PATH I99
J 0
(-6002 4125);
DISPLAY 0.872340 (-6002 4125);
PAINT GREEN (-6002 4125);
DISPLAY INVISIBLE (-6002 4125);
FORCEADD DNS..2
(-8350 2225);
PAINT RED (-8350 2225);
FORCEPROP 2 LAST CDS_LIB mstr_misc
J 0
(-8350 2225);
DISPLAY INVISIBLE (-8350 2225);
FORCEPROP 1 LAST COMMENT_BODY TRUE
R 1
J 0
(-8275 2000);
DISPLAY 0.872340 (-8275 2000);
PAINT PEACH (-8275 2000);
DISPLAY INVISIBLE (-8275 2000);
FORCEADD QUANTA_TITLE_BLOCK_C..1
(0 0);
FORCEPROP 0 LAST CDS_CON_LAST_MODIFIED Thu Sep 14 16:12:13 2023
J 0
(-1885 15);
DISPLAY INVISIBLE (-1885 15);
FORCEPROP 1 LAST CUSTOM_TXT_CDS <CON_LAST_MODIFIED>
J 0
(-1885 15);
DISPLAY 0.978723 (-1885 15);
FORCEPROP 2 LAST CUSTOM_TXT_CDS <XR_PAGE_TITLE>
J 0
(-7890 5250);
DISPLAY 0.638298 (-7890 5250);
PAINT PINK (-7890 5250);
DISPLAY INVISIBLE (-7890 5250);
FORCEPROP 1 LAST CUSTOM_TXT_CDS <NAME_2>
J 0
(-3175 50);
FORCEPROP 1 LAST CUSTOM_TXT_CDS <NAME_1>
J 0
(-3175 175);
FORCEPROP 1 LAST CUSTOM_TXT_CDS <Q_NUMBER>
J 0
(-1403 103);
DISPLAY 1.212766 (-1403 103);
FORCEPROP 1 LAST CUSTOM_TXT_CDS <Q_PROJ>
J 0
(-2382 102);
DISPLAY 1.212766 (-2382 102);
FORCEPROP 1 LAST CUSTOM_TXT_CDS <Q_REV>
J 0
(-184 103);
DISPLAY 1.212766 (-184 103);
FORCEPROP 1 LAST CUSTOM_TXT_CDS <CON_PAGE_NUM> OF <CON_TOTAL_PAGES>
J 0
(-446 18);
DISPLAY 0.978723 (-446 18);
FORCEPROP 1 LAST Q_TITLE DDR5 - CPU1 CHK
J 0
(-9366 26);
DISPLAY 2.446809 (-9366 26);
PAINT GREEN (-9366 26);
FORCEPROP 2 LAST CDS_LIB pure_quanta
J 0
(0 0);
DISPLAY INVISIBLE (0 0);
FORCEPROP 1 LAST CDS_LMAN_SYM_OUTLINE -9475,6775,100,-125
J 0
(0 0);
DISPLAY 0.468085 (0 0);
PAINT GREEN (0 0);
DISPLAY INVISIBLE (0 0);
FORCEPROP 2 LAST PAGE_BORDER TRUE
J 0
(-7890 5250);
DISPLAY 0.638298 (-7890 5250);
PAINT PINK (-7890 5250);
DISPLAY INVISIBLE (-7890 5250);
FORCEPROP 2 LAST CDS_XR_PAGE_TITLE CR-108 : @T6G_MB_LIB.T6G(SCH_1):PAGE108
J 0
(-7890 5250);
DISPLAY 0.638298 (-7890 5250);
PAINT PINK (-7890 5250);
DISPLAY INVISIBLE (-7890 5250);
FORCEPROP 1 LAST Q_DEPT BU9
J 1
(-3763 49);
DISPLAY 1.957447 (-3763 49);
PAINT GREEN (-3763 49);
DISPLAY INVISIBLE (-3763 49);
FORCEPROP 1 LAST COMMENT_BODY TRUE
J 0
(12 -13);
DISPLAY 0.978723 (12 -13);
PAINT GREEN (12 -13);
DISPLAY INVISIBLE (12 -13);
WIRE 17 -1 (-3425 4550)(-3425 4525);
WIRE 17 -1 (-3425 4550)(-2525 4550);
FORCEPROP 2 LAST SIG_NAME M_K_CPU1_SA_DQS_DP<9:0>
J 0
(-3160 4560);
DISPLAY 0.489362 (-3160 4560);
WIRE 17 -1 (-3425 3500)(-3425 3475);
WIRE 17 -1 (-3425 3500)(-2525 3500);
FORCEPROP 2 LAST SIG_NAME M_K_CPU1_SB_DQS_DP<9:0>
J 0
(-3160 3510);
DISPLAY 0.489362 (-3160 3510);
WIRE 17 -1 (-3225 3450)(-3225 3425);
WIRE 17 -1 (-3225 3450)(-2525 3450);
FORCEPROP 2 LAST SIG_NAME M_K_CPU1_SB_DQS_DN<9:0>
J 0
(-3160 3460);
DISPLAY 0.489362 (-3160 3460);
WIRE 17 -1 (-3225 4500)(-3225 4475);
WIRE 17 -1 (-3225 4500)(-2525 4500);
FORCEPROP 2 LAST SIG_NAME M_K_CPU1_SA_DQS_DN<9:0>
J 0
(-3160 4510);
DISPLAY 0.489362 (-3160 4510);
WIRE 17 -1 (-3425 4525)(-3425 4425);
WIRE 17 -1 (-3425 4425)(-3425 4325);
WIRE 17 -1 (-3425 4325)(-3425 4225);
WIRE 17 -1 (-3225 4475)(-3225 4375);
WIRE 17 -1 (-3225 4375)(-3225 4275);
WIRE 17 -1 (-3225 4275)(-3225 4175);
WIRE 17 -1 (-3225 3325)(-3225 3225);
WIRE 17 -1 (-3225 3425)(-3225 3325);
WIRE 17 -1 (-3225 3225)(-3225 3125);
WIRE 17 -1 (-3225 3125)(-3225 3025);
WIRE 17 -1 (-3425 4225)(-3425 4125);
WIRE 17 -1 (-3425 3275)(-3425 3175);
WIRE 17 -1 (-3425 3375)(-3425 3275);
WIRE 17 -1 (-3425 3175)(-3425 3075);
WIRE 17 -1 (-3425 2975)(-3425 3075);
WIRE 17 -1 (-3425 3475)(-3425 3375);
WIRE 17 -1 (-3425 2875)(-3425 2975);
WIRE 17 -1 (-3425 2775)(-3425 2875);
WIRE 17 -1 (-3225 2925)(-3225 3025);
WIRE 17 -1 (-3225 2825)(-3225 2925);
WIRE 17 -1 (-3225 2725)(-3225 2825);
WIRE 17 -1 (-3225 4175)(-3225 4075);
WIRE 17 -1 (-3225 3975)(-3225 4075);
WIRE 17 -1 (-3225 3875)(-3225 3975);
WIRE 17 -1 (-3225 3775)(-3225 3875);
WIRE 17 -1 (-3425 2775)(-3425 2675);
WIRE 17 -1 (-3225 2725)(-3225 2625);
WIRE 17 -1 (-3425 4025)(-3425 4125);
WIRE 17 -1 (-3425 3925)(-3425 4025);
WIRE 17 -1 (-3425 3825)(-3425 3925);
WIRE 17 -1 (-3425 3825)(-3425 3725);
WIRE 17 -1 (-3225 3775)(-3225 3675);
WIRE 17 -1 (-3425 2675)(-3425 2575);
WIRE 17 -1 (-3225 2625)(-3225 2525);
WIRE 17 -1 (-3425 3725)(-3425 3625);
WIRE 17 -1 (-3225 3675)(-3225 3575);
WIRE 17 -1 (-5950 2150)(-5950 2200);
WIRE 17 -1 (-5950 2200)(-5950 2250);
WIRE 17 -1 (-5950 2250)(-5950 2300);
WIRE 17 -1 (-5950 2300)(-5950 2350);
WIRE 17 -1 (-5950 2400)(-5950 2350);
WIRE 17 -1 (-5950 2450)(-5950 2400);
WIRE 17 -1 (-5950 2500)(-5950 2450);
WIRE 17 -1 (-5950 2550)(-5950 2500);
WIRE 17 -1 (-5950 2600)(-5950 2550);
WIRE 17 -1 (-5950 2650)(-5950 2600);
WIRE 17 -1 (-5950 2700)(-5950 2650);
WIRE 17 -1 (-5950 2750)(-5950 2700);
WIRE 17 -1 (-5950 2750)(-5950 2800);
WIRE 17 -1 (-5950 2800)(-5950 2850);
WIRE 17 -1 (-5950 2850)(-5950 2900);
WIRE 17 -1 (-5950 2900)(-5950 2950);
WIRE 17 -1 (-5950 3000)(-5950 2950);
WIRE 17 -1 (-5950 3050)(-5950 3000);
WIRE 17 -1 (-5950 3100)(-5950 3050);
WIRE 17 -1 (-5950 3150)(-5950 3100);
WIRE 17 -1 (-5950 3200)(-5950 3150);
WIRE 17 -1 (-5950 3250)(-5950 3200);
WIRE 17 -1 (-5950 3300)(-5950 3250);
WIRE 17 -1 (-5950 3350)(-5950 3300);
WIRE 17 -1 (-5950 3400)(-5950 3350);
WIRE 17 -1 (-5950 3450)(-5950 3400);
WIRE 17 -1 (-5950 3500)(-5950 3450);
WIRE 17 -1 (-5950 3550)(-5950 3500);
WIRE 17 -1 (-5950 3600)(-5950 3550);
WIRE 17 -1 (-5950 3650)(-5950 3600);
WIRE 17 -1 (-5950 3700)(-5950 3650);
WIRE 17 -1 (-5950 3725)(-5950 3700);
WIRE 17 -1 (-5950 3725)(-5375 3725);
FORCEPROP 2 LAST SIG_NAME M_K_CPU1_SB_DQ<31:0>
J 0
(-5885 3735);
DISPLAY 0.489362 (-5885 3735);
WIRE 17 -1 (-5950 3800)(-5950 3850);
WIRE 17 -1 (-5950 3850)(-5950 3900);
WIRE 17 -1 (-5950 3900)(-5950 3950);
WIRE 17 -1 (-5950 3950)(-5950 4000);
WIRE 17 -1 (-5950 4050)(-5950 4000);
WIRE 17 -1 (-5950 4100)(-5950 4050);
WIRE 17 -1 (-5950 4150)(-5950 4100);
WIRE 17 -1 (-5950 4200)(-5950 4150);
WIRE 17 -1 (-5950 4250)(-5950 4200);
WIRE 17 -1 (-5950 4300)(-5950 4250);
WIRE 17 -1 (-5950 4350)(-5950 4300);
WIRE 17 -1 (-5950 4400)(-5950 4350);
WIRE 17 -1 (-5950 4400)(-5950 4450);
WIRE 17 -1 (-5950 4450)(-5950 4500);
WIRE 17 -1 (-5950 4500)(-5950 4550);
WIRE 17 -1 (-5950 4550)(-5950 4600);
WIRE 17 -1 (-5950 4650)(-5950 4600);
WIRE 17 -1 (-5950 4700)(-5950 4650);
WIRE 17 -1 (-5950 4750)(-5950 4700);
WIRE 17 -1 (-5950 4800)(-5950 4750);
WIRE 17 -1 (-5950 4850)(-5950 4800);
WIRE 17 -1 (-5950 4900)(-5950 4850);
WIRE 17 -1 (-5950 4950)(-5950 4900);
WIRE 17 -1 (-5950 5000)(-5950 4950);
WIRE 17 -1 (-5950 5050)(-5950 5000);
WIRE 17 -1 (-5950 5100)(-5950 5050);
WIRE 17 -1 (-5950 5150)(-5950 5100);
WIRE 17 -1 (-5950 5200)(-5950 5150);
WIRE 17 -1 (-5950 5250)(-5950 5200);
WIRE 17 -1 (-5950 5300)(-5950 5250);
WIRE 17 -1 (-5950 5350)(-5950 5300);
WIRE 17 -1 (-5950 5375)(-5950 5350);
WIRE 17 -1 (-5950 5375)(-5375 5375);
FORCEPROP 2 LAST SIG_NAME M_K_CPU1_SA_DQ<31:0>
J 0
(-5885 5385);
DISPLAY 0.489362 (-5885 5385);
WIRE 17 -1 (-7750 3150)(-7750 3200);
WIRE 17 -1 (-7750 3200)(-7750 3250);
WIRE 17 -1 (-7750 3250)(-7750 3300);
WIRE 17 -1 (-7750 3300)(-7750 3350);
WIRE 17 -1 (-7750 3400)(-7750 3350);
WIRE 17 -1 (-7750 3400)(-7750 3450);
WIRE 17 -1 (-7750 3500)(-7750 3450);
WIRE 17 -1 (-7750 3500)(-7750 3525);
WIRE 17 -1 (-7750 3525)(-8250 3525);
FORCEPROP 2 LAST SIG_NAME M_K_CPU1_SB_CB<7:0>
J 0
(-8200 3535);
DISPLAY 0.489362 (-8200 3535);
WIRE 17 -1 (-7750 3600)(-7750 3650);
WIRE 17 -1 (-7750 3650)(-7750 3700);
WIRE 17 -1 (-7750 3700)(-7750 3750);
WIRE 17 -1 (-7750 3750)(-7750 3800);
WIRE 17 -1 (-7750 3850)(-7750 3800);
WIRE 17 -1 (-7750 3850)(-7750 3900);
WIRE 17 -1 (-7750 3950)(-7750 3900);
WIRE 17 -1 (-7750 3950)(-7750 3975);
WIRE 17 -1 (-7750 3975)(-8250 3975);
FORCEPROP 2 LAST SIG_NAME M_K_CPU1_SA_CB<7:0>
J 0
(-8200 3985);
DISPLAY 0.489362 (-8200 3985);
WIRE 17 -1 (-7750 4950)(-7750 4975);
WIRE 17 -1 (-7750 4900)(-7750 4950);
WIRE 17 -1 (-7750 4975)(-8250 4975);
FORCEPROP 2 LAST SIG_NAME M_K_CPU1_SB_CA<6:0>
J 0
(-8235 4985);
DISPLAY 0.489362 (-8235 4985);
WIRE 17 -1 (-7750 5350)(-7750 5375);
WIRE 17 -1 (-7750 5300)(-7750 5350);
WIRE 17 -1 (-7750 5375)(-8250 5375);
FORCEPROP 2 LAST SIG_NAME M_K_CPU1_SA_CA<6:0>
J 0
(-8235 5385);
DISPLAY 0.489362 (-8235 5385);
WIRE 17 -1 (-7750 4850)(-7750 4900);
WIRE 17 -1 (-7750 5250)(-7750 5300);
WIRE 17 -1 (-7750 4800)(-7750 4850);
WIRE 17 -1 (-7750 4750)(-7750 4800);
WIRE 17 -1 (-7750 4700)(-7750 4750);
WIRE 17 -1 (-7750 5200)(-7750 5250);
WIRE 17 -1 (-7750 5150)(-7750 5200);
WIRE 17 -1 (-7750 5100)(-7750 5150);
WIRE 17 -1 (-7750 4650)(-7750 4700);
WIRE 17 -1 (-7750 5050)(-7750 5100);
WIRE 16 -1 (-6400 925)(-6400 1000);
WIRE 16 -1 (-8675 2975)(-8675 3050);
WIRE 16 -1 (-8375 2325)(-8375 2350);
WIRE 16 -1 (-7450 3275)(-7650 3275);
WIRE 16 -1 (-6250 5325)(-6050 5325);
WIRE 16 -1 (-7450 3925)(-7650 3925);
WIRE 16 -1 (-7450 3775)(-7650 3775);
WIRE 16 -1 (-7450 3625)(-7650 3625);
WIRE 16 -1 (-7450 3475)(-7650 3475);
WIRE 16 -1 (-7450 5025)(-7650 5025);
WIRE 16 -1 (-7450 4625)(-7650 4625);
WIRE 16 -1 (-7450 5075)(-7650 5075);
WIRE 16 -1 (-7450 4675)(-7650 4675);
WIRE 16 -1 (-7450 5125)(-7650 5125);
WIRE 16 -1 (-7450 4725)(-7650 4725);
WIRE 16 -1 (-7450 5175)(-7650 5175);
WIRE 16 -1 (-7450 4775)(-7650 4775);
WIRE 16 -1 (-7450 5225)(-7650 5225);
WIRE 16 -1 (-7450 4825)(-7650 4825);
WIRE 16 -1 (-7450 5275)(-7650 5275);
WIRE 16 -1 (-7450 4875)(-7650 4875);
WIRE 16 -1 (-7450 5325)(-7650 5325);
WIRE 16 -1 (-7450 4925)(-7650 4925);
WIRE 16 -1 (-7450 3875)(-7650 3875);
WIRE 16 -1 (-7450 3825)(-7650 3825);
WIRE 16 -1 (-7450 3725)(-7650 3725);
WIRE 16 -1 (-7450 3675)(-7650 3675);
WIRE 16 -1 (-7450 3575)(-7650 3575);
WIRE 16 -1 (-7450 3425)(-7650 3425);
WIRE 16 -1 (-7450 3375)(-7650 3375);
WIRE 16 -1 (-7450 3325)(-7650 3325);
WIRE 16 -1 (-7450 3225)(-7650 3225);
WIRE 16 -1 (-7450 3175)(-7650 3175);
WIRE 16 -1 (-7450 3125)(-7650 3125);
WIRE 16 -1 (-7450 4025)(-8250 4025);
FORCEPROP 2 LAST SIG_NAME M_K_CPU1_CLK_DN<0>
J 0
(-8200 4035);
DISPLAY 0.489362 (-8200 4035);
WIRE 16 -1 (-7450 4075)(-8250 4075);
FORCEPROP 2 LAST SIG_NAME M_K_CPU1_CLK_DP<0>
J 0
(-8200 4085);
DISPLAY 0.489362 (-8200 4085);
WIRE 16 -1 (-7450 4325)(-8250 4325);
FORCEPROP 2 LAST SIG_NAME M_K_CPU1_SA_CS_N<0>
J 0
(-8200 4335);
DISPLAY 0.489362 (-8200 4335);
WIRE 16 -1 (-7450 4175)(-8250 4175);
FORCEPROP 2 LAST SIG_NAME M_K_CPU1_SB_CS_N<0>
J 0
(-8200 4185);
DISPLAY 0.489362 (-8200 4185);
WIRE 16 -1 (-7450 4375)(-8250 4375);
FORCEPROP 2 LAST SIG_NAME M_K_CPU1_SA_CS_N<1>
J 0
(-8200 4385);
DISPLAY 0.489362 (-8200 4385);
WIRE 16 -1 (-7450 4225)(-8250 4225);
FORCEPROP 2 LAST SIG_NAME M_K_CPU1_SB_CS_N<1>
J 0
(-8200 4235);
DISPLAY 0.489362 (-8200 4235);
WIRE 16 -1 (-6050 5275)(-6250 5275);
WIRE 16 -1 (-6050 5225)(-6250 5225);
WIRE 16 -1 (-6050 5175)(-6250 5175);
WIRE 16 -1 (-6250 5125)(-6050 5125);
WIRE 16 -1 (-6050 5075)(-6250 5075);
WIRE 16 -1 (-6050 5025)(-6250 5025);
WIRE 16 -1 (-6050 4975)(-6250 4975);
WIRE 16 -1 (-6250 4925)(-6050 4925);
WIRE 16 -1 (-6050 4875)(-6250 4875);
WIRE 16 -1 (-6050 4825)(-6250 4825);
WIRE 16 -1 (-6050 4775)(-6250 4775);
WIRE 16 -1 (-6250 4725)(-6050 4725);
WIRE 16 -1 (-6050 4675)(-6250 4675);
WIRE 16 -1 (-6050 4625)(-6250 4625);
WIRE 16 -1 (-6050 4575)(-6250 4575);
WIRE 16 -1 (-6250 4525)(-6050 4525);
WIRE 16 -1 (-6050 4475)(-6250 4475);
WIRE 16 -1 (-6050 4425)(-6250 4425);
WIRE 16 -1 (-6050 4375)(-6250 4375);
WIRE 16 -1 (-6250 4325)(-6050 4325);
WIRE 16 -1 (-6050 4275)(-6250 4275);
WIRE 16 -1 (-6050 4225)(-6250 4225);
WIRE 16 -1 (-6050 4175)(-6250 4175);
WIRE 16 -1 (-6250 4125)(-6050 4125);
WIRE 16 -1 (-6050 4075)(-6250 4075);
WIRE 16 -1 (-6050 4025)(-6250 4025);
WIRE 16 -1 (-6050 3975)(-6250 3975);
WIRE 16 -1 (-6250 3925)(-6050 3925);
WIRE 16 -1 (-6050 3875)(-6250 3875);
WIRE 16 -1 (-6050 3825)(-6250 3825);
WIRE 16 -1 (-6050 3775)(-6250 3775);
WIRE 16 -1 (-6250 3675)(-6050 3675);
WIRE 16 -1 (-6050 3625)(-6250 3625);
WIRE 16 -1 (-6050 3575)(-6250 3575);
WIRE 16 -1 (-6050 3525)(-6250 3525);
WIRE 16 -1 (-6250 3475)(-6050 3475);
WIRE 16 -1 (-6050 3425)(-6250 3425);
WIRE 16 -1 (-6050 3375)(-6250 3375);
WIRE 16 -1 (-6050 3325)(-6250 3325);
WIRE 16 -1 (-6250 3275)(-6050 3275);
WIRE 16 -1 (-6050 3225)(-6250 3225);
WIRE 16 -1 (-6050 3175)(-6250 3175);
WIRE 16 -1 (-6050 3125)(-6250 3125);
WIRE 16 -1 (-6250 3075)(-6050 3075);
WIRE 16 -1 (-6050 3025)(-6250 3025);
WIRE 16 -1 (-6050 2975)(-6250 2975);
WIRE 16 -1 (-6050 2925)(-6250 2925);
WIRE 16 -1 (-6250 2875)(-6050 2875);
WIRE 16 -1 (-6050 2825)(-6250 2825);
WIRE 16 -1 (-6050 2775)(-6250 2775);
WIRE 16 -1 (-6050 2725)(-6250 2725);
WIRE 16 -1 (-6250 2675)(-6050 2675);
WIRE 16 -1 (-6050 2625)(-6250 2625);
WIRE 16 -1 (-6050 2575)(-6250 2575);
WIRE 16 -1 (-6050 2525)(-6250 2525);
WIRE 16 -1 (-6250 2475)(-6050 2475);
WIRE 16 -1 (-6050 2425)(-6250 2425);
WIRE 16 -1 (-6050 2375)(-6250 2375);
WIRE 16 -1 (-6050 2325)(-6250 2325);
WIRE 16 -1 (-6250 2275)(-6050 2275);
WIRE 16 -1 (-6050 2225)(-6250 2225);
WIRE 16 -1 (-6050 2175)(-6250 2175);
WIRE 16 -1 (-6050 2125)(-6250 2125);
WIRE 16 -1 (-7450 1925)(-8250 1925);
FORCEPROP 2 LAST SIG_NAME M_K_CPU1_SA_RSP<0>
J 0
(-8200 1935);
DISPLAY 0.489362 (-8200 1935);
WIRE 16 -1 (-7450 1875)(-8250 1875);
FORCEPROP 2 LAST SIG_NAME M_K_CPU1_SB_RSP<0>
J 0
(-8200 1885);
DISPLAY 0.489362 (-8200 1885);
WIRE 16 -1 (-7450 4525)(-8250 4525);
FORCEPROP 2 LAST SIG_NAME M_K_CPU1_SA_PAR
J 0
(-8200 4535);
DISPLAY 0.489362 (-8200 4535);
WIRE 16 -1 (-7450 4475)(-8250 4475);
FORCEPROP 2 LAST SIG_NAME M_K_CPU1_SB_PAR
J 0
(-8200 4485);
DISPLAY 0.489362 (-8200 4485);
WIRE 16 -1 (-3675 4250)(-3325 4250);
WIRE 16 -1 (-3525 4200)(-3675 4200);
WIRE 16 -1 (-3525 3350)(-3675 3350);
WIRE 16 -1 (-3675 3300)(-3325 3300);
WIRE 16 -1 (-3525 3250)(-3675 3250);
WIRE 16 -1 (-3675 3550)(-3325 3550);
WIRE 16 -1 (-3525 3600)(-3675 3600);
WIRE 16 -1 (-3675 2500)(-3325 2500);
WIRE 16 -1 (-3525 2550)(-3675 2550);
WIRE 16 -1 (-3675 3650)(-3325 3650);
WIRE 16 -1 (-3675 3700)(-3525 3700);
WIRE 16 -1 (-3675 2600)(-3325 2600);
WIRE 16 -1 (-3675 2650)(-3525 2650);
WIRE 16 -1 (-3675 3750)(-3325 3750);
WIRE 16 -1 (-3525 3800)(-3675 3800);
WIRE 16 -1 (-3675 2700)(-3325 2700);
WIRE 16 -1 (-3525 2750)(-3675 2750);
WIRE 16 -1 (-3675 3850)(-3325 3850);
WIRE 16 -1 (-3525 3900)(-3675 3900);
WIRE 16 -1 (-3675 2800)(-3325 2800);
WIRE 16 -1 (-3525 2850)(-3675 2850);
WIRE 16 -1 (-3675 3950)(-3325 3950);
WIRE 16 -1 (-3525 4000)(-3675 4000);
WIRE 16 -1 (-3675 2900)(-3325 2900);
WIRE 16 -1 (-3525 2950)(-3675 2950);
WIRE 16 -1 (-3675 4050)(-3325 4050);
WIRE 16 -1 (-3675 4100)(-3525 4100);
WIRE 16 -1 (-3675 3000)(-3325 3000);
WIRE 16 -1 (-3675 3050)(-3525 3050);
WIRE 16 -1 (-3675 4150)(-3325 4150);
WIRE 16 -1 (-3675 3100)(-3325 3100);
WIRE 16 -1 (-3525 3150)(-3675 3150);
WIRE 16 -1 (-3525 4300)(-3675 4300);
WIRE 16 -1 (-3675 3200)(-3325 3200);
WIRE 16 -1 (-3675 4350)(-3325 4350);
WIRE 16 -1 (-3525 4400)(-3675 4400);
WIRE 16 -1 (-3675 4450)(-3325 4450);
WIRE 16 -1 (-3675 3400)(-3325 3400);
WIRE 16 -1 (-3675 3450)(-3525 3450);
WIRE 16 -1 (-3675 4500)(-3525 4500);
WIRE 16 -1 (-6400 1275)(-6400 1200);
WIRE 16 -1 (-6400 1275)(-7125 1275);
FORCEPROP 2 LAST SIG_NAME PD_CHK_CPU1_DIMM_SAA
J 0
(-7110 1285);
DISPLAY 0.489362 (-7110 1285);
WIRE 16 -1 (-8600 2075)(-8975 2075);
FORCEPROP 2 LAST SIG_NAME PWRGD_CHGL_CPU1
J 0
(-8935 2085);
DISPLAY 0.489362 (-8935 2085);
WIRE 16 -1 (-7450 3025)(-8100 3025);
FORCEPROP 2 LAST SIG_NAME M_K_CPU1_RESET_N
J 0
(-8085 3035);
DISPLAY 0.489362 (-8085 3035);
WIRE 16 -1 (-7450 2975)(-8100 2975);
FORCEPROP 2 LAST SIG_NAME M_K_CPU1_ALERT_N
J 0
(-8085 2985);
DISPLAY 0.489362 (-8085 2985);
WIRE 16 -1 (-7450 2825)(-8500 2825);
FORCEPROP 2 LAST SIG_NAME PD_CHK_CPU1_DIMM_SAA
J 0
(-8475 2835);
DISPLAY 0.489362 (-8475 2835);
WIRE 16 -1 (-8575 2875)(-7450 2875);
WIRE 16 -1 (-8575 3275)(-8575 2875);
WIRE 16 -1 (-8575 3300)(-8575 3275);
WIRE 16 -1 (-8675 3275)(-8575 3275);
WIRE 16 -1 (-8675 3250)(-8675 3275);
WIRE 16 -1 (-2150 5175)(-1850 5175);
WIRE 16 -1 (-2150 5225)(-2150 5175);
WIRE 16 -1 (-1850 5225)(-2150 5225);
WIRE 16 -1 (-2150 5225)(-2150 5275);
WIRE 16 -1 (-1850 5275)(-2150 5275);
WIRE 16 -1 (-2150 5275)(-2150 6025);
WIRE 16 -1 (-2275 6025)(-2150 6025);
WIRE 16 -1 (-2275 6025)(-2275 5925);
WIRE 16 -1 (-2275 6025)(-2850 6025);
WIRE 16 -1 (-2850 5925)(-2850 6025);
WIRE 16 -1 (-2850 6025)(-2850 6100);
WIRE 16 -1 (-2275 5600)(-2275 5725);
WIRE 16 -1 (-2275 5600)(-2850 5600);
WIRE 16 -1 (-2850 5600)(-2850 5725);
WIRE 16 -1 (-2850 5600)(-2850 5525);
WIRE 16 -1 (-350 5275)(-350 5225);
WIRE 16 -1 (-350 5275)(-650 5275);
WIRE 16 -1 (-350 5225)(-350 5175);
WIRE 16 -1 (-350 5225)(-650 5225);
WIRE 16 -1 (-350 5175)(-350 5125);
WIRE 16 -1 (-350 5175)(-650 5175);
WIRE 16 -1 (-350 5125)(-650 5125);
WIRE 16 -1 (-350 5125)(-350 5075);
WIRE 16 -1 (-350 5075)(-350 5025);
WIRE 16 -1 (-350 5075)(-650 5075);
WIRE 16 -1 (-350 5025)(-350 4975);
WIRE 16 -1 (-350 5025)(-650 5025);
WIRE 16 -1 (-350 4975)(-350 4925);
WIRE 16 -1 (-350 4975)(-650 4975);
WIRE 16 -1 (-350 4925)(-350 4875);
WIRE 16 -1 (-350 4925)(-650 4925);
WIRE 16 -1 (-350 4875)(-350 4825);
WIRE 16 -1 (-350 4875)(-650 4875);
WIRE 16 -1 (-350 4825)(-350 4775);
WIRE 16 -1 (-350 4825)(-650 4825);
WIRE 16 -1 (-350 4775)(-350 4725);
WIRE 16 -1 (-350 4775)(-650 4775);
WIRE 16 -1 (-350 4725)(-350 4675);
WIRE 16 -1 (-350 4725)(-650 4725);
WIRE 16 -1 (-350 4675)(-350 4625);
WIRE 16 -1 (-350 4675)(-650 4675);
WIRE 16 -1 (-350 4625)(-350 4575);
WIRE 16 -1 (-350 4625)(-650 4625);
WIRE 16 -1 (-350 4575)(-350 4525);
WIRE 16 -1 (-350 4575)(-650 4575);
WIRE 16 -1 (-350 4525)(-350 4475);
WIRE 16 -1 (-350 4525)(-650 4525);
WIRE 16 -1 (-350 4475)(-350 4425);
WIRE 16 -1 (-350 4475)(-650 4475);
WIRE 16 -1 (-350 4425)(-350 4375);
WIRE 16 -1 (-350 4425)(-650 4425);
WIRE 16 -1 (-350 4375)(-350 4325);
WIRE 16 -1 (-350 4375)(-650 4375);
WIRE 16 -1 (-350 4325)(-350 4275);
WIRE 16 -1 (-350 4325)(-650 4325);
WIRE 16 -1 (-350 4275)(-350 4225);
WIRE 16 -1 (-350 4275)(-650 4275);
WIRE 16 -1 (-350 4225)(-350 4175);
WIRE 16 -1 (-350 4225)(-650 4225);
WIRE 16 -1 (-350 4175)(-350 4125);
WIRE 16 -1 (-350 4175)(-650 4175);
WIRE 16 -1 (-350 4125)(-650 4125);
WIRE 16 -1 (-350 4125)(-350 4075);
WIRE 16 -1 (-350 4075)(-350 4025);
WIRE 16 -1 (-350 4075)(-650 4075);
WIRE 16 -1 (-350 4025)(-350 3975);
WIRE 16 -1 (-350 4025)(-650 4025);
WIRE 16 -1 (-350 3975)(-350 3925);
WIRE 16 -1 (-350 3975)(-650 3975);
WIRE 16 -1 (-350 3925)(-350 3875);
WIRE 16 -1 (-350 3925)(-650 3925);
WIRE 16 -1 (-350 3875)(-350 3825);
WIRE 16 -1 (-350 3875)(-650 3875);
WIRE 16 -1 (-350 3825)(-350 3775);
WIRE 16 -1 (-350 3825)(-650 3825);
WIRE 16 -1 (-350 3775)(-350 3725);
WIRE 16 -1 (-350 3775)(-650 3775);
WIRE 16 -1 (-350 3725)(-350 3675);
WIRE 16 -1 (-350 3725)(-650 3725);
WIRE 16 -1 (-350 3675)(-350 3625);
WIRE 16 -1 (-350 3675)(-650 3675);
WIRE 16 -1 (-350 3625)(-350 3575);
WIRE 16 -1 (-350 3625)(-650 3625);
WIRE 16 -1 (-350 3575)(-350 3525);
WIRE 16 -1 (-350 3575)(-650 3575);
WIRE 16 -1 (-350 3525)(-350 3475);
WIRE 16 -1 (-350 3525)(-650 3525);
WIRE 16 -1 (-350 3475)(-350 3425);
WIRE 16 -1 (-350 3475)(-650 3475);
WIRE 16 -1 (-350 3425)(-350 3375);
WIRE 16 -1 (-350 3425)(-650 3425);
WIRE 16 -1 (-350 3375)(-350 3325);
WIRE 16 -1 (-350 3375)(-650 3375);
WIRE 16 -1 (-350 3325)(-350 3275);
WIRE 16 -1 (-350 3325)(-650 3325);
WIRE 16 -1 (-350 3275)(-350 3225);
WIRE 16 -1 (-350 3275)(-650 3275);
WIRE 16 -1 (-350 3225)(-350 3175);
WIRE 16 -1 (-350 3225)(-650 3225);
WIRE 16 -1 (-350 3175)(-350 3125);
WIRE 16 -1 (-350 3175)(-650 3175);
WIRE 16 -1 (-350 3125)(-350 3075);
WIRE 16 -1 (-350 3125)(-650 3125);
WIRE 16 -1 (-350 3075)(-650 3075);
WIRE 16 -1 (-350 3075)(-350 3025);
WIRE 16 -1 (-350 3025)(-350 2975);
WIRE 16 -1 (-350 3025)(-650 3025);
WIRE 16 -1 (-350 2975)(-350 2925);
WIRE 16 -1 (-350 2975)(-650 2975);
WIRE 16 -1 (-350 2925)(-350 2875);
WIRE 16 -1 (-350 2925)(-650 2925);
WIRE 16 -1 (-350 2875)(-350 2825);
WIRE 16 -1 (-350 2875)(-650 2875);
WIRE 16 -1 (-350 2825)(-350 2775);
WIRE 16 -1 (-350 2825)(-650 2825);
WIRE 16 -1 (-350 2775)(-350 2725);
WIRE 16 -1 (-350 2775)(-650 2775);
WIRE 16 -1 (-350 2725)(-350 2675);
WIRE 16 -1 (-350 2725)(-650 2725);
WIRE 16 -1 (-350 2675)(-350 2625);
WIRE 16 -1 (-350 2675)(-650 2675);
WIRE 16 -1 (-350 2625)(-350 2575);
WIRE 16 -1 (-350 2625)(-650 2625);
WIRE 16 -1 (-350 2575)(-350 2525);
WIRE 16 -1 (-350 2575)(-650 2575);
WIRE 16 -1 (-350 2525)(-350 2475);
WIRE 16 -1 (-350 2525)(-650 2525);
WIRE 16 -1 (-350 2475)(-350 2425);
WIRE 16 -1 (-350 2475)(-650 2475);
WIRE 16 -1 (-350 2425)(-350 2375);
WIRE 16 -1 (-350 2425)(-650 2425);
WIRE 16 -1 (-350 2375)(-350 2325);
WIRE 16 -1 (-350 2375)(-650 2375);
WIRE 16 -1 (-350 2325)(-350 2275);
WIRE 16 -1 (-350 2325)(-650 2325);
WIRE 16 -1 (-350 2275)(-350 2225);
WIRE 16 -1 (-350 2275)(-650 2275);
WIRE 16 -1 (-350 2225)(-350 2175);
WIRE 16 -1 (-350 2225)(-650 2225);
WIRE 16 -1 (-350 2175)(-350 2125);
WIRE 16 -1 (-350 2175)(-650 2175);
WIRE 16 -1 (-350 2125)(-650 2125);
WIRE 16 -1 (-350 2125)(-350 2025);
WIRE 16 -1 (-350 2025)(-350 1975);
WIRE 16 -1 (-350 2025)(-650 2025);
WIRE 16 -1 (-350 1975)(-350 1925);
WIRE 16 -1 (-350 1975)(-650 1975);
WIRE 16 -1 (-350 1925)(-350 1675);
WIRE 16 -1 (-350 1925)(-650 1925);
WIRE 16 -1 (-1850 5125)(-2150 5125);
WIRE 16 -1 (-2150 5125)(-2150 5075);
WIRE 16 -1 (-1850 5075)(-2150 5075);
WIRE 16 -1 (-2150 5075)(-2150 5025);
WIRE 16 -1 (-1850 5025)(-2150 5025);
WIRE 16 -1 (-2150 5025)(-2150 4975);
WIRE 16 -1 (-1850 4975)(-2150 4975);
WIRE 16 -1 (-2150 4975)(-2150 4925);
WIRE 16 -1 (-1850 4925)(-2150 4925);
WIRE 16 -1 (-2150 4925)(-2150 4875);
WIRE 16 -1 (-1850 4875)(-2150 4875);
WIRE 16 -1 (-2150 4875)(-2150 4825);
WIRE 16 -1 (-1850 4825)(-2150 4825);
WIRE 16 -1 (-2150 4825)(-2150 4775);
WIRE 16 -1 (-1850 4775)(-2150 4775);
WIRE 16 -1 (-2150 4775)(-2150 4725);
WIRE 16 -1 (-1850 4725)(-2150 4725);
WIRE 16 -1 (-2150 4725)(-2150 4675);
WIRE 16 -1 (-1850 4675)(-2150 4675);
WIRE 16 -1 (-2150 4675)(-2150 4625);
WIRE 16 -1 (-1850 4625)(-2150 4625);
WIRE 16 -1 (-2150 4625)(-2150 4575);
WIRE 16 -1 (-1850 4575)(-2150 4575);
WIRE 16 -1 (-2150 4575)(-2150 4525);
WIRE 16 -1 (-1850 4525)(-2150 4525);
WIRE 16 -1 (-2150 4525)(-2150 4475);
WIRE 16 -1 (-1850 4475)(-2150 4475);
WIRE 16 -1 (-2150 4475)(-2150 4425);
WIRE 16 -1 (-1850 4425)(-2150 4425);
WIRE 16 -1 (-2150 4425)(-2150 4375);
WIRE 16 -1 (-1850 4375)(-2150 4375);
WIRE 16 -1 (-2150 4375)(-2150 4325);
WIRE 16 -1 (-1850 4325)(-2150 4325);
WIRE 16 -1 (-2150 4325)(-2150 4275);
WIRE 16 -1 (-1850 4275)(-2150 4275);
WIRE 16 -1 (-2150 4275)(-2150 4225);
WIRE 16 -1 (-1850 4225)(-2150 4225);
WIRE 16 -1 (-2150 4225)(-2150 4175);
WIRE 16 -1 (-1850 4175)(-2150 4175);
WIRE 16 -1 (-2150 4175)(-2150 4125);
WIRE 16 -1 (-1850 4125)(-2150 4125);
WIRE 16 -1 (-2150 4125)(-2150 4075);
WIRE 16 -1 (-1850 4075)(-2150 4075);
WIRE 16 -1 (-2150 4075)(-2150 4025);
WIRE 16 -1 (-1850 4025)(-2150 4025);
WIRE 16 -1 (-2150 4025)(-2150 3975);
WIRE 16 -1 (-1850 3975)(-2150 3975);
WIRE 16 -1 (-2150 3975)(-2150 3925);
WIRE 16 -1 (-1850 3925)(-2150 3925);
WIRE 16 -1 (-2150 3925)(-2150 3875);
WIRE 16 -1 (-1850 3875)(-2150 3875);
WIRE 16 -1 (-2150 3875)(-2150 3825);
WIRE 16 -1 (-1850 3825)(-2150 3825);
WIRE 16 -1 (-2150 3825)(-2150 3775);
WIRE 16 -1 (-1850 3775)(-2150 3775);
WIRE 16 -1 (-2150 3775)(-2150 3725);
WIRE 16 -1 (-1850 3725)(-2150 3725);
WIRE 16 -1 (-2150 3725)(-2150 3675);
WIRE 16 -1 (-1850 3675)(-2150 3675);
WIRE 16 -1 (-2150 3675)(-2150 3625);
WIRE 16 -1 (-1850 3625)(-2150 3625);
WIRE 16 -1 (-2150 3625)(-2150 3575);
WIRE 16 -1 (-1850 3575)(-2150 3575);
WIRE 16 -1 (-2150 3575)(-2150 3525);
WIRE 16 -1 (-1850 3525)(-2150 3525);
WIRE 16 -1 (-2150 3525)(-2150 3475);
WIRE 16 -1 (-1850 3475)(-2150 3475);
WIRE 16 -1 (-2150 3475)(-2150 3425);
WIRE 16 -1 (-1850 3425)(-2150 3425);
WIRE 16 -1 (-2150 3425)(-2150 3375);
WIRE 16 -1 (-1850 3375)(-2150 3375);
WIRE 16 -1 (-2150 3375)(-2150 3325);
WIRE 16 -1 (-1850 3325)(-2150 3325);
WIRE 16 -1 (-2150 3325)(-2150 3275);
WIRE 16 -1 (-1850 3275)(-2150 3275);
WIRE 16 -1 (-2150 3275)(-2150 3225);
WIRE 16 -1 (-1850 3225)(-2150 3225);
WIRE 16 -1 (-2150 3225)(-2150 3175);
WIRE 16 -1 (-1850 3175)(-2150 3175);
WIRE 16 -1 (-2150 3175)(-2150 3125);
WIRE 16 -1 (-1850 3125)(-2150 3125);
WIRE 16 -1 (-2150 3125)(-2150 3075);
WIRE 16 -1 (-1850 3075)(-2150 3075);
WIRE 16 -1 (-2150 3075)(-2150 3025);
WIRE 16 -1 (-1850 3025)(-2150 3025);
WIRE 16 -1 (-2150 3025)(-2150 2975);
WIRE 16 -1 (-1850 2975)(-2150 2975);
WIRE 16 -1 (-2150 2975)(-2150 2925);
WIRE 16 -1 (-1850 2925)(-2150 2925);
WIRE 16 -1 (-2150 2925)(-2150 2875);
WIRE 16 -1 (-1850 2875)(-2150 2875);
WIRE 16 -1 (-2150 2875)(-2150 2825);
WIRE 16 -1 (-1850 2825)(-2150 2825);
WIRE 16 -1 (-2150 2825)(-2150 2775);
WIRE 16 -1 (-1850 2775)(-2150 2775);
WIRE 16 -1 (-2150 2775)(-2150 2725);
WIRE 16 -1 (-1850 2725)(-2150 2725);
WIRE 16 -1 (-2150 2725)(-2150 2675);
WIRE 16 -1 (-1850 2675)(-2150 2675);
WIRE 16 -1 (-2150 2675)(-2150 2625);
WIRE 16 -1 (-1850 2625)(-2150 2625);
WIRE 16 -1 (-2150 2625)(-2150 2575);
WIRE 16 -1 (-1850 2575)(-2150 2575);
WIRE 16 -1 (-2150 2575)(-2150 2525);
WIRE 16 -1 (-1850 2525)(-2150 2525);
WIRE 16 -1 (-2150 2525)(-2150 2475);
WIRE 16 -1 (-1850 2475)(-2150 2475);
WIRE 16 -1 (-2150 2475)(-2150 2425);
WIRE 16 -1 (-1850 2425)(-2150 2425);
WIRE 16 -1 (-2150 2425)(-2150 2375);
WIRE 16 -1 (-1850 2375)(-2150 2375);
WIRE 16 -1 (-2150 2375)(-2150 2325);
WIRE 16 -1 (-1850 2325)(-2150 2325);
WIRE 16 -1 (-2150 2325)(-2150 2275);
WIRE 16 -1 (-1850 2275)(-2150 2275);
WIRE 16 -1 (-2150 2275)(-2150 2225);
WIRE 16 -1 (-1850 2225)(-2150 2225);
WIRE 16 -1 (-2150 2225)(-2150 2175);
WIRE 16 -1 (-1850 2175)(-2150 2175);
WIRE 16 -1 (-2150 2175)(-2150 2125);
WIRE 16 -1 (-1850 2125)(-2150 2125);
WIRE 16 -1 (-2150 2125)(-2150 2075);
WIRE 16 -1 (-1850 2075)(-2150 2075);
WIRE 16 -1 (-2150 2075)(-2150 2025);
WIRE 16 -1 (-1850 2025)(-2150 2025);
WIRE 16 -1 (-2150 2025)(-2150 1900);
WIRE 16 -1 (-7450 2725)(-7550 2725);
FORCEPROP 2 LAST SIG_NAME I3C_SPD_DDRK_CPU1_SCL
J 0
(-7935 2735);
DISPLAY 0.446809 (-7935 2735);
FORCEPROP 2 LASTPROP $XRERR UNIQUE?
J 0
(-8175 2735);
DISPLAY 0.638298 (-8175 2735);
PAINT MONO (-8175 2735);
DISPLAY INVISIBLE (-8175 2735);
WIRE 16 -1 (-7550 2725)(-7550 2550);
WIRE 16 -1 (-7550 2550)(-7650 2550);
WIRE 16 -1 (-7450 2775)(-8025 2775);
FORCEPROP 2 LAST SIG_NAME I3C_SPD_DDRK_CPU1_SDA
J 0
(-7935 2785);
DISPLAY 0.446809 (-7935 2785);
FORCEPROP 2 LASTPROP $XRERR UNIQUE?
J 0
(-8175 2785);
DISPLAY 0.638298 (-8175 2785);
PAINT MONO (-8175 2785);
DISPLAY INVISIBLE (-8175 2785);
WIRE 16 -1 (-8250 2775)(-8225 2775);
WIRE 16 -1 (-8250 2650)(-8250 2775);
WIRE 16 -1 (-8250 2650)(-8750 2650);
FORCEPROP 2 LAST SIG_NAME I3C_SPD_DDRGL_CPU1_SDA
J 0
(-8760 2660);
DISPLAY 0.489362 (-8760 2660);
WIRE 16 -1 (-8150 2075)(-8150 2475);
WIRE 16 -1 (-8150 2075)(-8375 2075);
WIRE 16 -1 (-7450 2475)(-8150 2475);
FORCEPROP 2 LAST SIG_NAME PWRGD_CHK_CPU1_DIMM
J 0
(-8035 2485);
DISPLAY 0.489362 (-8035 2485);
FORCEPROP 2 LASTPROP $XRERR UNIQUE?
J 0
(-8275 2485);
DISPLAY 0.638298 (-8275 2485);
PAINT MONO (-8275 2485);
DISPLAY INVISIBLE (-8275 2485);
WIRE 16 -1 (-8375 2125)(-8375 2075);
WIRE 16 -1 (-8375 2075)(-8400 2075);
WIRE 16 -1 (-7850 2550)(-8300 2550);
FORCEPROP 2 LAST SIG_NAME I3C_SPD_DDRGL_CPU1_SCL
J 0
(-8335 2560);
DISPLAY 0.489362 (-8335 2560);
DOT 1 (-8575 3275);
DOT 1 (-2150 4675);
DOT 1 (-350 5225);
DOT 1 (-350 5175);
DOT 1 (-350 5075);
DOT 1 (-350 5125);
DOT 1 (-350 5025);
DOT 1 (-350 4975);
DOT 1 (-350 4875);
DOT 1 (-350 4825);
DOT 1 (-350 4775);
DOT 1 (-350 4675);
DOT 1 (-350 4725);
DOT 1 (-350 4625);
DOT 1 (-350 4425);
DOT 1 (-350 4375);
DOT 1 (-350 4325);
DOT 1 (-350 4275);
DOT 1 (-350 4175);
DOT 1 (-350 4225);
DOT 1 (-350 4125);
DOT 1 (-350 4075);
DOT 1 (-350 4025);
DOT 1 (-350 3975);
DOT 1 (-350 3925);
DOT 1 (-350 3875);
DOT 1 (-350 3825);
DOT 1 (-350 3775);
DOT 1 (-2150 5275);
DOT 1 (-2150 5225);
DOT 1 (-2150 5075);
DOT 1 (-2150 4925);
DOT 1 (-2150 4875);
DOT 1 (-2150 4825);
DOT 1 (-2150 4775);
DOT 1 (-2150 4725);
DOT 1 (-2150 4625);
DOT 1 (-2150 4575);
DOT 1 (-2150 4525);
DOT 1 (-2150 4425);
DOT 1 (-2150 4475);
DOT 1 (-2150 4375);
DOT 1 (-2150 4325);
DOT 1 (-2150 4275);
DOT 1 (-2150 4225);
DOT 1 (-2150 4175);
DOT 1 (-2150 4125);
DOT 1 (-2150 4075);
DOT 1 (-2150 4025);
DOT 1 (-2150 3975);
DOT 1 (-2150 3925);
DOT 1 (-2150 3875);
DOT 1 (-2150 3775);
DOT 1 (-2150 3825);
DOT 1 (-350 3725);
DOT 1 (-350 3675);
DOT 1 (-350 3625);
DOT 1 (-350 3575);
DOT 1 (-350 3525);
DOT 1 (-350 3475);
DOT 1 (-350 3425);
DOT 1 (-350 3375);
DOT 1 (-350 3275);
DOT 1 (-350 3325);
DOT 1 (-350 3225);
DOT 1 (-350 3175);
DOT 1 (-350 3125);
DOT 1 (-350 3025);
DOT 1 (-350 3075);
DOT 1 (-350 2975);
DOT 1 (-350 2925);
DOT 1 (-350 2875);
DOT 1 (-350 2825);
DOT 1 (-350 2775);
DOT 1 (-350 2725);
DOT 1 (-350 2625);
DOT 1 (-350 2675);
DOT 1 (-350 2575);
DOT 1 (-350 2525);
DOT 1 (-350 2475);
DOT 1 (-350 2375);
DOT 1 (-350 2425);
DOT 1 (-350 2325);
DOT 1 (-350 2275);
DOT 1 (-350 2225);
DOT 1 (-350 2125);
DOT 1 (-350 2175);
DOT 1 (-350 2025);
DOT 1 (-350 1975);
DOT 1 (-350 1925);
DOT 1 (-2150 3725);
DOT 1 (-2150 3675);
DOT 1 (-2150 3625);
DOT 1 (-2150 3575);
DOT 1 (-2150 3525);
DOT 1 (-2150 3475);
DOT 1 (-2150 3425);
DOT 1 (-2150 3375);
DOT 1 (-2150 3325);
DOT 1 (-2150 3275);
DOT 1 (-2150 3225);
DOT 1 (-2150 3175);
DOT 1 (-2150 3125);
DOT 1 (-2150 3075);
DOT 1 (-2150 3025);
DOT 1 (-2150 2975);
DOT 1 (-2150 2925);
DOT 1 (-2150 2875);
DOT 1 (-2150 2825);
DOT 1 (-2150 2775);
DOT 1 (-2150 2725);
DOT 1 (-2150 2625);
DOT 1 (-2150 2675);
DOT 1 (-2150 2575);
DOT 1 (-2150 2525);
DOT 1 (-2150 2475);
DOT 1 (-2150 2375);
DOT 1 (-2150 2425);
DOT 1 (-2150 2325);
DOT 1 (-2150 2275);
DOT 1 (-2150 2225);
DOT 1 (-2150 2125);
DOT 1 (-2150 2175);
DOT 1 (-2150 2075);
DOT 1 (-2150 2025);
DOT 1 (-8375 2075);
DOT 1 (-2850 5600);
DOT 1 (-2850 6025);
DOT 1 (-2275 6025);
DOT 1 (-2150 5025);
DOT 1 (-2150 4975);
DOT 1 (-350 4475);
DOT 1 (-350 4525);
DOT 1 (-350 4575);
DOT 1 (-350 4925);
QUIT
